FILE_TYPE = MACRO_DRAWING;
SET COLOR_WIRE YELLOW;
SET COLOR_PROP ORANGE;
SET COLOR_DOT WHITE;
SET COLOR_ARC YELLOW;
SET COLOR_BODY GREEN;
SET COLOR_NOTE PURPLE;
SET PROP_DISPLAY VALUE;
SET PAGE_NUMBER P88;
FORCEADD GND..1
(-2250 1950);
FORCEPROP 3 LASTPIN (-2250 2000) SIG_NAME GND\g
J 0
(-2240 2010);
DISPLAY 0.659574 (-2240 2010);
PAINT MONO (-2240 2010);
DISPLAY INVISIBLE (-2240 2010);
FORCEPROP 2 LAST CDS_LIB mstr_symbols
J 0
(-2250 1950);
DISPLAY 0.723404 (-2250 1950);
DISPLAY INVISIBLE (-2250 1950);
FORCEPROP 1 LAST SIZE 1B
J 0
(-2175 1900);
DISPLAY 0.851064 (-2175 1900);
PAINT GREEN (-2175 1900);
DISPLAY INVISIBLE (-2175 1900);
FORCEPROP 1 LAST BODY_TYPE PLUMBING
J 0
(-2295 1907);
DISPLAY 0.340426 (-2295 1907);
PAINT GREEN (-2295 1907);
DISPLAY INVISIBLE (-2295 1907);
FORCEPROP 1 LAST PATH I150
J 0
(-2175 1950);
DISPLAY 0.872340 (-2175 1950);
PAINT GREEN (-2175 1950);
DISPLAY INVISIBLE (-2175 1950);
FORCEPROP 1 LAST VOLTAGE 0.0
J 0
(-2295 1907);
DISPLAY 0.723404 (-2295 1907);
PAINT SKYBLUE (-2295 1907);
DISPLAY INVISIBLE (-2295 1907);
FORCEPROP 1 LAST HDL_POWER GND
J 0
(-2250 2100);
DISPLAY 0.851064 (-2250 2100);
PAINT GREEN (-2250 2100);
DISPLAY INVISIBLE (-2250 2100);
FORCEADD GND..1
(-450 1750);
FORCEPROP 3 LASTPIN (-450 1800) SIG_NAME GND\g
J 0
(-440 1810);
DISPLAY 0.659574 (-440 1810);
PAINT MONO (-440 1810);
DISPLAY INVISIBLE (-440 1810);
FORCEPROP 2 LAST CDS_LIB mstr_symbols
J 0
(-450 1750);
DISPLAY 0.723404 (-450 1750);
DISPLAY INVISIBLE (-450 1750);
FORCEPROP 1 LAST SIZE 1B
J 0
(-375 1700);
DISPLAY 0.851064 (-375 1700);
PAINT GREEN (-375 1700);
DISPLAY INVISIBLE (-375 1700);
FORCEPROP 1 LAST BODY_TYPE PLUMBING
J 0
(-495 1707);
DISPLAY 0.340426 (-495 1707);
PAINT GREEN (-495 1707);
DISPLAY INVISIBLE (-495 1707);
FORCEPROP 1 LAST PATH I152
J 0
(-375 1750);
DISPLAY 0.872340 (-375 1750);
PAINT GREEN (-375 1750);
DISPLAY INVISIBLE (-375 1750);
FORCEPROP 1 LAST VOLTAGE 0.0
J 0
(-495 1707);
DISPLAY 0.723404 (-495 1707);
PAINT SKYBLUE (-495 1707);
DISPLAY INVISIBLE (-495 1707);
FORCEPROP 1 LAST HDL_POWER GND
J 0
(-450 1900);
DISPLAY 0.851064 (-450 1900);
PAINT GREEN (-450 1900);
DISPLAY INVISIBLE (-450 1900);
FORCEADD OFFPAGE..5
(-8375 2100);
FORCEPROP 2 LAST $XR0 13 
J 0
(-8629 2100);
DISPLAY 0.638298 (-8629 2100);
PAINT MONO (-8629 2100);
FORCEPROP 2 LAST PATH I167
J 0
(-8325 2175);
DISPLAY 0.808511 (-8325 2175);
DISPLAY INVISIBLE (-8325 2175);
FORCEPROP 1 LAST COMMENT_BODY TRUE
J 0
(-8275 2025);
DISPLAY 0.872340 (-8275 2025);
PAINT GREEN (-8275 2025);
DISPLAY INVISIBLE (-8275 2025);
FORCEPROP 1 LAST OFFPAGE TRUE
J 0
(-8050 1975);
DISPLAY 0.872340 (-8050 1975);
PAINT GREEN (-8050 1975);
DISPLAY INVISIBLE (-8050 1975);
FORCEPROP 2 LAST CDS_LIB mstr_standard
J 0
(-8375 2100);
DISPLAY 0.808511 (-8375 2100);
DISPLAY INVISIBLE (-8375 2100);
FORCEADD OFFPAGE..5
(-8375 2150);
FORCEPROP 2 LAST $XR0 13 
J 0
(-8629 2150);
DISPLAY 0.638298 (-8629 2150);
PAINT MONO (-8629 2150);
FORCEPROP 2 LAST PATH I171
J 0
(-8325 2225);
DISPLAY 0.808511 (-8325 2225);
DISPLAY INVISIBLE (-8325 2225);
FORCEPROP 1 LAST COMMENT_BODY TRUE
J 0
(-8275 2075);
DISPLAY 0.872340 (-8275 2075);
PAINT GREEN (-8275 2075);
DISPLAY INVISIBLE (-8275 2075);
FORCEPROP 1 LAST OFFPAGE TRUE
J 0
(-8050 2025);
DISPLAY 0.872340 (-8050 2025);
PAINT GREEN (-8050 2025);
DISPLAY INVISIBLE (-8050 2025);
FORCEPROP 2 LAST CDS_LIB mstr_standard
J 0
(-8375 2150);
DISPLAY 0.808511 (-8375 2150);
DISPLAY INVISIBLE (-8375 2150);
FORCEADD OFFPAGE..6
(-8375 3750);
FORCEPROP 2 LAST $XR0 13 
J 0
(-8654 3750);
DISPLAY 0.638298 (-8654 3750);
PAINT MONO (-8654 3750);
FORCEPROP 2 LAST PATH I174
J 0
(-8325 3825);
DISPLAY 0.808511 (-8325 3825);
DISPLAY INVISIBLE (-8325 3825);
FORCEPROP 1 LAST COMMENT_BODY TRUE
J 0
(-8275 3675);
DISPLAY 0.872340 (-8275 3675);
PAINT GREEN (-8275 3675);
DISPLAY INVISIBLE (-8275 3675);
FORCEPROP 1 LAST OFFPAGE TRUE
J 0
(-8050 3625);
DISPLAY 0.872340 (-8050 3625);
PAINT GREEN (-8050 3625);
DISPLAY INVISIBLE (-8050 3625);
FORCEPROP 2 LAST CDS_LIB mstr_standard
J 0
(-8375 3750);
DISPLAY 0.723404 (-8375 3750);
PAINT MONO (-8375 3750);
DISPLAY INVISIBLE (-8375 3750);
FORCEADD VCC_CORE..1
(-8475 3625);
FORCEPROP 3 LASTPIN (-8475 3575) SIG_NAME P3V3_STBY\g
J 0
(-8465 3585);
DISPLAY 0.659574 (-8465 3585);
PAINT MONO (-8465 3585);
DISPLAY INVISIBLE (-8465 3585);
FORCEPROP 1 LAST HDL_POWER P3V3_STBY
J 1
(-8475 3675);
DISPLAY 0.489362 (-8475 3675);
PAINT GREEN (-8475 3675);
FORCEPROP 2 LAST CDS_LIB mstr_symbols
J 0
(-8475 3625);
PAINT MONO (-8475 3625);
DISPLAY INVISIBLE (-8475 3625);
FORCEPROP 1 LAST PATH I175
J 0
(-8425 3650);
DISPLAY 0.872340 (-8425 3650);
PAINT GREEN (-8425 3650);
DISPLAY INVISIBLE (-8425 3650);
FORCEPROP 0 LAST VOLTAGE 3.3
J 0
(-8750 3775);
DISPLAY 1.021277 (-8750 3775);
PAINT SKYBLUE (-8750 3775);
DISPLAY INVISIBLE (-8750 3775);
FORCEPROP 2 LAST ROOM PVCCINFAON_CPU0_CTRL
J 0
(-8475 3725);
DISPLAY 0.808511 (-8475 3725);
PAINT RED (-8475 3725);
DISPLAY INVISIBLE (-8475 3725);
FORCEADD OFFPAGE..1
(-8100 3250);
FORCEPROP 2 LAST $XR0 13 
J 0
(-8321 3250);
DISPLAY 0.638298 (-8321 3250);
PAINT MONO (-8321 3250);
FORCEPROP 2 LAST PATH I177
J 0
(-8300 3475);
DISPLAY 0.808511 (-8300 3475);
DISPLAY INVISIBLE (-8300 3475);
FORCEPROP 1 LAST COMMENT_BODY TRUE
J 0
(-7975 3150);
DISPLAY 0.872340 (-7975 3150);
PAINT GREEN (-7975 3150);
DISPLAY INVISIBLE (-7975 3150);
FORCEPROP 1 LAST OFFPAGE TRUE
J 0
(-7775 3125);
DISPLAY 0.872340 (-7775 3125);
PAINT GREEN (-7775 3125);
DISPLAY INVISIBLE (-7775 3125);
FORCEPROP 2 LAST CDS_LIB mstr_standard
J 0
(-8100 3250);
DISPLAY 0.808511 (-8100 3250);
DISPLAY INVISIBLE (-8100 3250);
FORCEADD OFFPAGE..6
(-8375 4200);
FORCEPROP 2 LAST $XR0 13 
J 0
(-8654 4200);
DISPLAY 0.638298 (-8654 4200);
PAINT MONO (-8654 4200);
FORCEPROP 2 LAST PATH I178
J 0
(-8325 4275);
DISPLAY 0.808511 (-8325 4275);
DISPLAY INVISIBLE (-8325 4275);
FORCEPROP 1 LAST COMMENT_BODY TRUE
J 0
(-8275 4125);
DISPLAY 0.872340 (-8275 4125);
PAINT GREEN (-8275 4125);
DISPLAY INVISIBLE (-8275 4125);
FORCEPROP 1 LAST OFFPAGE TRUE
J 0
(-8050 4075);
DISPLAY 0.872340 (-8050 4075);
PAINT GREEN (-8050 4075);
DISPLAY INVISIBLE (-8050 4075);
FORCEPROP 2 LAST CDS_LIB mstr_standard
J 0
(-8375 4200);
DISPLAY 0.723404 (-8375 4200);
PAINT MONO (-8375 4200);
DISPLAY INVISIBLE (-8375 4200);
FORCEADD OFFPAGE..1
(-8375 4300);
FORCEPROP 2 LAST $XR0 13 
J 0
(-8626 4300);
DISPLAY 0.638298 (-8626 4300);
PAINT MONO (-8626 4300);
FORCEPROP 2 LAST PATH I179
J 0
(-8325 4375);
DISPLAY 0.808511 (-8325 4375);
DISPLAY INVISIBLE (-8325 4375);
FORCEPROP 1 LAST COMMENT_BODY TRUE
J 0
(-8250 4200);
DISPLAY 0.872340 (-8250 4200);
PAINT GREEN (-8250 4200);
DISPLAY INVISIBLE (-8250 4200);
FORCEPROP 1 LAST OFFPAGE TRUE
J 0
(-8050 4175);
DISPLAY 0.872340 (-8050 4175);
PAINT GREEN (-8050 4175);
DISPLAY INVISIBLE (-8050 4175);
FORCEPROP 2 LAST CDS_LIB mstr_standard
J 0
(-8375 4300);
DISPLAY 0.723404 (-8375 4300);
PAINT MONO (-8375 4300);
DISPLAY INVISIBLE (-8375 4300);
FORCEADD OFFPAGE..1
(-8375 4250);
FORCEPROP 2 LAST $XR0 13 
J 0
(-8626 4250);
DISPLAY 0.638298 (-8626 4250);
PAINT MONO (-8626 4250);
FORCEPROP 2 LAST PATH I180
J 0
(-8325 4325);
DISPLAY 0.808511 (-8325 4325);
DISPLAY INVISIBLE (-8325 4325);
FORCEPROP 1 LAST COMMENT_BODY TRUE
J 0
(-8250 4150);
DISPLAY 0.872340 (-8250 4150);
PAINT GREEN (-8250 4150);
DISPLAY INVISIBLE (-8250 4150);
FORCEPROP 1 LAST OFFPAGE TRUE
J 0
(-8050 4125);
DISPLAY 0.872340 (-8050 4125);
PAINT GREEN (-8050 4125);
DISPLAY INVISIBLE (-8050 4125);
FORCEPROP 2 LAST CDS_LIB mstr_standard
J 0
(-8375 4250);
DISPLAY 0.808511 (-8375 4250);
DISPLAY INVISIBLE (-8375 4250);
FORCEADD OFFPAGE..1
(-8375 4400);
FORCEPROP 2 LAST $XR0 13 
J 0
(-8626 4400);
DISPLAY 0.638298 (-8626 4400);
PAINT MONO (-8626 4400);
FORCEPROP 2 LAST PATH I181
J 0
(-8325 4475);
DISPLAY 0.808511 (-8325 4475);
DISPLAY INVISIBLE (-8325 4475);
FORCEPROP 1 LAST COMMENT_BODY TRUE
J 0
(-8250 4300);
DISPLAY 0.872340 (-8250 4300);
PAINT GREEN (-8250 4300);
DISPLAY INVISIBLE (-8250 4300);
FORCEPROP 1 LAST OFFPAGE TRUE
J 0
(-8050 4275);
DISPLAY 0.872340 (-8050 4275);
PAINT GREEN (-8050 4275);
DISPLAY INVISIBLE (-8050 4275);
FORCEPROP 2 LAST CDS_LIB mstr_standard
J 0
(-8375 4400);
DISPLAY 0.808511 (-8375 4400);
DISPLAY INVISIBLE (-8375 4400);
FORCEADD OFFPAGE..1
(-8375 4600);
FORCEPROP 2 LAST $XR0 13 
J 0
(-8626 4600);
DISPLAY 0.638298 (-8626 4600);
PAINT MONO (-8626 4600);
FORCEPROP 2 LAST PATH I182
J 0
(-8325 4675);
DISPLAY 0.808511 (-8325 4675);
DISPLAY INVISIBLE (-8325 4675);
FORCEPROP 1 LAST COMMENT_BODY TRUE
J 0
(-8250 4500);
DISPLAY 0.872340 (-8250 4500);
PAINT GREEN (-8250 4500);
DISPLAY INVISIBLE (-8250 4500);
FORCEPROP 1 LAST OFFPAGE TRUE
J 0
(-8050 4475);
DISPLAY 0.872340 (-8050 4475);
PAINT GREEN (-8050 4475);
DISPLAY INVISIBLE (-8050 4475);
FORCEPROP 2 LAST CDS_LIB mstr_standard
J 0
(-8375 4600);
DISPLAY 0.723404 (-8375 4600);
PAINT MONO (-8375 4600);
DISPLAY INVISIBLE (-8375 4600);
FORCEADD OFFPAGE..1
(-8375 4550);
FORCEPROP 2 LAST $XR0 13 
J 0
(-8626 4550);
DISPLAY 0.638298 (-8626 4550);
PAINT MONO (-8626 4550);
FORCEPROP 2 LAST PATH I183
J 0
(-8325 4625);
DISPLAY 0.808511 (-8325 4625);
DISPLAY INVISIBLE (-8325 4625);
FORCEPROP 1 LAST COMMENT_BODY TRUE
J 0
(-8250 4450);
DISPLAY 0.872340 (-8250 4450);
PAINT GREEN (-8250 4450);
DISPLAY INVISIBLE (-8250 4450);
FORCEPROP 1 LAST OFFPAGE TRUE
J 0
(-8050 4425);
DISPLAY 0.872340 (-8050 4425);
PAINT GREEN (-8050 4425);
DISPLAY INVISIBLE (-8050 4425);
FORCEPROP 2 LAST CDS_LIB mstr_standard
J 0
(-8375 4550);
DISPLAY 0.808511 (-8375 4550);
DISPLAY INVISIBLE (-8375 4550);
FORCEADD OFFPAGE..1
(-8375 4450);
FORCEPROP 2 LAST $XR0 13 
J 0
(-8626 4450);
DISPLAY 0.638298 (-8626 4450);
PAINT MONO (-8626 4450);
FORCEPROP 2 LAST PATH I184
J 0
(-8325 4525);
DISPLAY 0.808511 (-8325 4525);
DISPLAY INVISIBLE (-8325 4525);
FORCEPROP 1 LAST COMMENT_BODY TRUE
J 0
(-8250 4350);
DISPLAY 0.872340 (-8250 4350);
PAINT GREEN (-8250 4350);
DISPLAY INVISIBLE (-8250 4350);
FORCEPROP 1 LAST OFFPAGE TRUE
J 0
(-8050 4325);
DISPLAY 0.872340 (-8050 4325);
PAINT GREEN (-8050 4325);
DISPLAY INVISIBLE (-8050 4325);
FORCEPROP 2 LAST CDS_LIB mstr_standard
J 0
(-8375 4450);
DISPLAY 0.723404 (-8375 4450);
PAINT MONO (-8375 4450);
DISPLAY INVISIBLE (-8375 4450);
FORCEADD OFFPAGE..1
(-8375 4700);
FORCEPROP 2 LAST $XR0 13 
J 0
(-8626 4700);
DISPLAY 0.638298 (-8626 4700);
PAINT MONO (-8626 4700);
FORCEPROP 2 LAST PATH I185
J 0
(-8325 4775);
DISPLAY 0.808511 (-8325 4775);
DISPLAY INVISIBLE (-8325 4775);
FORCEPROP 1 LAST COMMENT_BODY TRUE
J 0
(-8250 4600);
DISPLAY 0.872340 (-8250 4600);
PAINT GREEN (-8250 4600);
DISPLAY INVISIBLE (-8250 4600);
FORCEPROP 1 LAST OFFPAGE TRUE
J 0
(-8050 4575);
DISPLAY 0.872340 (-8050 4575);
PAINT GREEN (-8050 4575);
DISPLAY INVISIBLE (-8050 4575);
FORCEPROP 2 LAST CDS_LIB mstr_standard
J 0
(-8375 4700);
DISPLAY 0.808511 (-8375 4700);
DISPLAY INVISIBLE (-8375 4700);
FORCEADD OFFPAGE..1
(-8375 4750);
FORCEPROP 2 LAST $XR0 13 
J 0
(-8626 4750);
DISPLAY 0.638298 (-8626 4750);
PAINT MONO (-8626 4750);
FORCEPROP 2 LAST PATH I186
J 0
(-8325 4825);
DISPLAY 0.808511 (-8325 4825);
DISPLAY INVISIBLE (-8325 4825);
FORCEPROP 1 LAST COMMENT_BODY TRUE
J 0
(-8250 4650);
DISPLAY 0.872340 (-8250 4650);
PAINT GREEN (-8250 4650);
DISPLAY INVISIBLE (-8250 4650);
FORCEPROP 1 LAST OFFPAGE TRUE
J 0
(-8050 4625);
DISPLAY 0.872340 (-8050 4625);
PAINT GREEN (-8050 4625);
DISPLAY INVISIBLE (-8050 4625);
FORCEPROP 2 LAST CDS_LIB mstr_standard
J 0
(-8375 4750);
DISPLAY 0.723404 (-8375 4750);
PAINT MONO (-8375 4750);
DISPLAY INVISIBLE (-8375 4750);
FORCEADD OFFPAGE..1
(-8375 5200);
FORCEPROP 2 LAST $XR0 13 
J 0
(-8626 5200);
DISPLAY 0.638298 (-8626 5200);
PAINT MONO (-8626 5200);
FORCEPROP 2 LAST PATH I187
J 0
(-8325 5275);
DISPLAY 0.808511 (-8325 5275);
DISPLAY INVISIBLE (-8325 5275);
FORCEPROP 1 LAST COMMENT_BODY TRUE
J 0
(-8250 5100);
DISPLAY 0.872340 (-8250 5100);
PAINT GREEN (-8250 5100);
DISPLAY INVISIBLE (-8250 5100);
FORCEPROP 1 LAST OFFPAGE TRUE
J 0
(-8050 5075);
DISPLAY 0.872340 (-8050 5075);
PAINT GREEN (-8050 5075);
DISPLAY INVISIBLE (-8050 5075);
FORCEPROP 2 LAST CDS_LIB mstr_standard
J 0
(-8375 5200);
DISPLAY 0.723404 (-8375 5200);
PAINT MONO (-8375 5200);
DISPLAY INVISIBLE (-8375 5200);
FORCEADD OFFPAGE..1
(-8375 5600);
FORCEPROP 2 LAST $XR0 13 
J 0
(-8626 5600);
DISPLAY 0.638298 (-8626 5600);
PAINT MONO (-8626 5600);
FORCEPROP 2 LAST PATH I188
J 0
(-8325 5675);
DISPLAY 0.808511 (-8325 5675);
DISPLAY INVISIBLE (-8325 5675);
FORCEPROP 1 LAST COMMENT_BODY TRUE
J 0
(-8250 5500);
DISPLAY 0.872340 (-8250 5500);
PAINT GREEN (-8250 5500);
DISPLAY INVISIBLE (-8250 5500);
FORCEPROP 1 LAST OFFPAGE TRUE
J 0
(-8050 5475);
DISPLAY 0.872340 (-8050 5475);
PAINT GREEN (-8050 5475);
DISPLAY INVISIBLE (-8050 5475);
FORCEPROP 2 LAST CDS_LIB mstr_standard
J 0
(-8375 5600);
DISPLAY 0.723404 (-8375 5600);
PAINT MONO (-8375 5600);
DISPLAY INVISIBLE (-8375 5600);
FORCEADD TAP..1
R 2
(-7775 3350);
FORCEPROP 3 LASTPIN (-7725 3350) SIG_NAME M_D_CPU0_SB_CB<0>
J 0
(-7715 3360);
DISPLAY 0.659574 (-7715 3360);
PAINT MONO (-7715 3360);
DISPLAY INVISIBLE (-7715 3360);
FORCEPROP 1 LASTPIN (-7725 3350) BN 0
J 2
(-7713 3358);
DISPLAY 0.489362 (-7713 3358);
PAINT GREEN (-7713 3358);
FORCEPROP 2 LAST CDS_LIB mstr_standard
J 0
(-7775 3350);
DISPLAY 0.723404 (-7775 3350);
PAINT MONO (-7775 3350);
DISPLAY INVISIBLE (-7775 3350);
FORCEPROP 1 LAST BODY_TYPE PLUMBING
J 2
(-7775 3400);
DISPLAY 0.872340 (-7775 3400);
PAINT GREEN (-7775 3400);
DISPLAY INVISIBLE (-7775 3400);
FORCEPROP 1 LAST HDL_TAP TRUE
J 2
(-8100 3225);
DISPLAY 0.872340 (-8100 3225);
DISPLAY INVISIBLE (-8100 3225);
FORCEPROP 1 LAST PATH I189
J 2
(-7773 3350);
DISPLAY 0.872340 (-7773 3350);
PAINT GREEN (-7773 3350);
DISPLAY INVISIBLE (-7773 3350);
FORCEADD TAP..1
R 2
(-7775 3400);
FORCEPROP 3 LASTPIN (-7725 3400) SIG_NAME M_D_CPU0_SB_CB<1>
J 0
(-7715 3410);
DISPLAY 0.659574 (-7715 3410);
PAINT MONO (-7715 3410);
DISPLAY INVISIBLE (-7715 3410);
FORCEPROP 1 LASTPIN (-7725 3400) BN 1
J 2
(-7713 3408);
DISPLAY 0.489362 (-7713 3408);
PAINT GREEN (-7713 3408);
FORCEPROP 2 LAST CDS_LIB mstr_standard
J 0
(-7775 3400);
DISPLAY 0.723404 (-7775 3400);
PAINT MONO (-7775 3400);
DISPLAY INVISIBLE (-7775 3400);
FORCEPROP 1 LAST BODY_TYPE PLUMBING
J 2
(-7775 3450);
DISPLAY 0.872340 (-7775 3450);
PAINT GREEN (-7775 3450);
DISPLAY INVISIBLE (-7775 3450);
FORCEPROP 1 LAST HDL_TAP TRUE
J 2
(-8100 3275);
DISPLAY 0.872340 (-8100 3275);
DISPLAY INVISIBLE (-8100 3275);
FORCEPROP 1 LAST PATH I190
J 2
(-7773 3400);
DISPLAY 0.872340 (-7773 3400);
PAINT GREEN (-7773 3400);
DISPLAY INVISIBLE (-7773 3400);
FORCEADD TAP..1
R 2
(-7775 3500);
FORCEPROP 3 LASTPIN (-7725 3500) SIG_NAME M_D_CPU0_SB_CB<3>
J 0
(-7715 3510);
DISPLAY 0.659574 (-7715 3510);
PAINT MONO (-7715 3510);
DISPLAY INVISIBLE (-7715 3510);
FORCEPROP 1 LASTPIN (-7725 3500) BN 3
J 2
(-7713 3508);
DISPLAY 0.489362 (-7713 3508);
PAINT GREEN (-7713 3508);
FORCEPROP 2 LAST CDS_LIB mstr_standard
J 0
(-7775 3500);
DISPLAY 0.723404 (-7775 3500);
PAINT MONO (-7775 3500);
DISPLAY INVISIBLE (-7775 3500);
FORCEPROP 1 LAST BODY_TYPE PLUMBING
J 2
(-7775 3550);
DISPLAY 0.872340 (-7775 3550);
PAINT GREEN (-7775 3550);
DISPLAY INVISIBLE (-7775 3550);
FORCEPROP 1 LAST HDL_TAP TRUE
J 2
(-8100 3375);
DISPLAY 0.872340 (-8100 3375);
DISPLAY INVISIBLE (-8100 3375);
FORCEPROP 1 LAST PATH I191
J 2
(-7773 3500);
DISPLAY 0.872340 (-7773 3500);
PAINT GREEN (-7773 3500);
DISPLAY INVISIBLE (-7773 3500);
FORCEADD TAP..1
R 2
(-7775 3450);
FORCEPROP 3 LASTPIN (-7725 3450) SIG_NAME M_D_CPU0_SB_CB<2>
J 0
(-7715 3460);
DISPLAY 0.659574 (-7715 3460);
PAINT MONO (-7715 3460);
DISPLAY INVISIBLE (-7715 3460);
FORCEPROP 1 LASTPIN (-7725 3450) BN 2
J 2
(-7713 3458);
DISPLAY 0.489362 (-7713 3458);
PAINT GREEN (-7713 3458);
FORCEPROP 2 LAST CDS_LIB mstr_standard
J 0
(-7775 3450);
DISPLAY 0.723404 (-7775 3450);
PAINT MONO (-7775 3450);
DISPLAY INVISIBLE (-7775 3450);
FORCEPROP 1 LAST BODY_TYPE PLUMBING
J 2
(-7775 3500);
DISPLAY 0.872340 (-7775 3500);
PAINT GREEN (-7775 3500);
DISPLAY INVISIBLE (-7775 3500);
FORCEPROP 1 LAST HDL_TAP TRUE
J 2
(-8100 3325);
DISPLAY 0.872340 (-8100 3325);
DISPLAY INVISIBLE (-8100 3325);
FORCEPROP 1 LAST PATH I192
J 2
(-7773 3450);
DISPLAY 0.872340 (-7773 3450);
PAINT GREEN (-7773 3450);
DISPLAY INVISIBLE (-7773 3450);
FORCEADD TAP..1
R 2
(-7775 3550);
FORCEPROP 3 LASTPIN (-7725 3550) SIG_NAME M_D_CPU0_SB_CB<4>
J 0
(-7715 3560);
DISPLAY 0.659574 (-7715 3560);
PAINT MONO (-7715 3560);
DISPLAY INVISIBLE (-7715 3560);
FORCEPROP 1 LASTPIN (-7725 3550) BN 4
J 2
(-7713 3558);
DISPLAY 0.489362 (-7713 3558);
PAINT GREEN (-7713 3558);
FORCEPROP 2 LAST CDS_LIB mstr_standard
J 0
(-7775 3550);
DISPLAY 0.723404 (-7775 3550);
PAINT MONO (-7775 3550);
DISPLAY INVISIBLE (-7775 3550);
FORCEPROP 1 LAST BODY_TYPE PLUMBING
J 2
(-7775 3600);
DISPLAY 0.872340 (-7775 3600);
PAINT GREEN (-7775 3600);
DISPLAY INVISIBLE (-7775 3600);
FORCEPROP 1 LAST HDL_TAP TRUE
J 2
(-8100 3425);
DISPLAY 0.872340 (-8100 3425);
DISPLAY INVISIBLE (-8100 3425);
FORCEPROP 1 LAST PATH I193
J 2
(-7773 3550);
DISPLAY 0.872340 (-7773 3550);
PAINT GREEN (-7773 3550);
DISPLAY INVISIBLE (-7773 3550);
FORCEADD TAP..1
R 2
(-7775 3600);
FORCEPROP 3 LASTPIN (-7725 3600) SIG_NAME M_D_CPU0_SB_CB<5>
J 0
(-7715 3610);
DISPLAY 0.659574 (-7715 3610);
PAINT MONO (-7715 3610);
DISPLAY INVISIBLE (-7715 3610);
FORCEPROP 1 LASTPIN (-7725 3600) BN 5
J 2
(-7713 3608);
DISPLAY 0.489362 (-7713 3608);
PAINT GREEN (-7713 3608);
FORCEPROP 2 LAST CDS_LIB mstr_standard
J 0
(-7775 3600);
DISPLAY 0.723404 (-7775 3600);
PAINT MONO (-7775 3600);
DISPLAY INVISIBLE (-7775 3600);
FORCEPROP 1 LAST BODY_TYPE PLUMBING
J 2
(-7775 3650);
DISPLAY 0.872340 (-7775 3650);
PAINT GREEN (-7775 3650);
DISPLAY INVISIBLE (-7775 3650);
FORCEPROP 1 LAST HDL_TAP TRUE
J 2
(-8100 3475);
DISPLAY 0.872340 (-8100 3475);
DISPLAY INVISIBLE (-8100 3475);
FORCEPROP 1 LAST PATH I194
J 2
(-7773 3600);
DISPLAY 0.872340 (-7773 3600);
PAINT GREEN (-7773 3600);
DISPLAY INVISIBLE (-7773 3600);
FORCEADD TAP..1
R 2
(-7775 3650);
FORCEPROP 3 LASTPIN (-7725 3650) SIG_NAME M_D_CPU0_SB_CB<6>
J 0
(-7715 3660);
DISPLAY 0.659574 (-7715 3660);
PAINT MONO (-7715 3660);
DISPLAY INVISIBLE (-7715 3660);
FORCEPROP 1 LASTPIN (-7725 3650) BN 6
J 2
(-7713 3658);
DISPLAY 0.489362 (-7713 3658);
PAINT GREEN (-7713 3658);
FORCEPROP 2 LAST CDS_LIB mstr_standard
J 0
(-7775 3650);
DISPLAY 0.723404 (-7775 3650);
PAINT MONO (-7775 3650);
DISPLAY INVISIBLE (-7775 3650);
FORCEPROP 1 LAST BODY_TYPE PLUMBING
J 2
(-7775 3700);
DISPLAY 0.872340 (-7775 3700);
PAINT GREEN (-7775 3700);
DISPLAY INVISIBLE (-7775 3700);
FORCEPROP 1 LAST HDL_TAP TRUE
J 2
(-8100 3525);
DISPLAY 0.872340 (-8100 3525);
DISPLAY INVISIBLE (-8100 3525);
FORCEPROP 1 LAST PATH I195
J 2
(-7773 3650);
DISPLAY 0.872340 (-7773 3650);
PAINT GREEN (-7773 3650);
DISPLAY INVISIBLE (-7773 3650);
FORCEADD TAP..1
R 2
(-7775 3700);
FORCEPROP 3 LASTPIN (-7725 3700) SIG_NAME M_D_CPU0_SB_CB<7>
J 0
(-7715 3710);
DISPLAY 0.659574 (-7715 3710);
PAINT MONO (-7715 3710);
DISPLAY INVISIBLE (-7715 3710);
FORCEPROP 1 LASTPIN (-7725 3700) BN 7
J 2
(-7713 3708);
DISPLAY 0.489362 (-7713 3708);
PAINT GREEN (-7713 3708);
FORCEPROP 2 LAST CDS_LIB mstr_standard
J 0
(-7775 3700);
DISPLAY 0.723404 (-7775 3700);
PAINT MONO (-7775 3700);
DISPLAY INVISIBLE (-7775 3700);
FORCEPROP 1 LAST BODY_TYPE PLUMBING
J 2
(-7775 3750);
DISPLAY 0.872340 (-7775 3750);
PAINT GREEN (-7775 3750);
DISPLAY INVISIBLE (-7775 3750);
FORCEPROP 1 LAST HDL_TAP TRUE
J 2
(-8100 3575);
DISPLAY 0.872340 (-8100 3575);
DISPLAY INVISIBLE (-8100 3575);
FORCEPROP 1 LAST PATH I196
J 2
(-7773 3700);
DISPLAY 0.872340 (-7773 3700);
PAINT GREEN (-7773 3700);
DISPLAY INVISIBLE (-7773 3700);
FORCEADD TAP..1
R 2
(-7775 3800);
FORCEPROP 3 LASTPIN (-7725 3800) SIG_NAME M_D_CPU0_SA_CB<0>
J 0
(-7715 3810);
DISPLAY 0.659574 (-7715 3810);
PAINT MONO (-7715 3810);
DISPLAY INVISIBLE (-7715 3810);
FORCEPROP 1 LASTPIN (-7725 3800) BN 0
J 2
(-7713 3808);
DISPLAY 0.489362 (-7713 3808);
PAINT GREEN (-7713 3808);
FORCEPROP 2 LAST CDS_LIB mstr_standard
J 0
(-7775 3800);
DISPLAY 0.723404 (-7775 3800);
PAINT MONO (-7775 3800);
DISPLAY INVISIBLE (-7775 3800);
FORCEPROP 1 LAST BODY_TYPE PLUMBING
J 2
(-7775 3850);
DISPLAY 0.872340 (-7775 3850);
PAINT GREEN (-7775 3850);
DISPLAY INVISIBLE (-7775 3850);
FORCEPROP 1 LAST HDL_TAP TRUE
J 2
(-8100 3675);
DISPLAY 0.872340 (-8100 3675);
DISPLAY INVISIBLE (-8100 3675);
FORCEPROP 1 LAST PATH I197
J 2
(-7773 3800);
DISPLAY 0.872340 (-7773 3800);
PAINT GREEN (-7773 3800);
DISPLAY INVISIBLE (-7773 3800);
FORCEADD TAP..1
R 2
(-7775 3850);
FORCEPROP 3 LASTPIN (-7725 3850) SIG_NAME M_D_CPU0_SA_CB<1>
J 0
(-7715 3860);
DISPLAY 0.659574 (-7715 3860);
PAINT MONO (-7715 3860);
DISPLAY INVISIBLE (-7715 3860);
FORCEPROP 1 LASTPIN (-7725 3850) BN 1
J 2
(-7713 3858);
DISPLAY 0.489362 (-7713 3858);
PAINT GREEN (-7713 3858);
FORCEPROP 2 LAST CDS_LIB mstr_standard
J 0
(-7775 3850);
DISPLAY 0.723404 (-7775 3850);
PAINT MONO (-7775 3850);
DISPLAY INVISIBLE (-7775 3850);
FORCEPROP 1 LAST BODY_TYPE PLUMBING
J 2
(-7775 3900);
DISPLAY 0.872340 (-7775 3900);
PAINT GREEN (-7775 3900);
DISPLAY INVISIBLE (-7775 3900);
FORCEPROP 1 LAST HDL_TAP TRUE
J 2
(-8100 3725);
DISPLAY 0.872340 (-8100 3725);
DISPLAY INVISIBLE (-8100 3725);
FORCEPROP 1 LAST PATH I198
J 2
(-7773 3850);
DISPLAY 0.872340 (-7773 3850);
PAINT GREEN (-7773 3850);
DISPLAY INVISIBLE (-7773 3850);
FORCEADD TAP..1
R 2
(-7775 3950);
FORCEPROP 3 LASTPIN (-7725 3950) SIG_NAME M_D_CPU0_SA_CB<3>
J 0
(-7715 3960);
DISPLAY 0.659574 (-7715 3960);
PAINT MONO (-7715 3960);
DISPLAY INVISIBLE (-7715 3960);
FORCEPROP 1 LASTPIN (-7725 3950) BN 3
J 2
(-7713 3958);
DISPLAY 0.489362 (-7713 3958);
PAINT GREEN (-7713 3958);
FORCEPROP 2 LAST CDS_LIB mstr_standard
J 0
(-7775 3950);
DISPLAY 0.723404 (-7775 3950);
PAINT MONO (-7775 3950);
DISPLAY INVISIBLE (-7775 3950);
FORCEPROP 1 LAST BODY_TYPE PLUMBING
J 2
(-7775 4000);
DISPLAY 0.872340 (-7775 4000);
PAINT GREEN (-7775 4000);
DISPLAY INVISIBLE (-7775 4000);
FORCEPROP 1 LAST HDL_TAP TRUE
J 2
(-8100 3825);
DISPLAY 0.872340 (-8100 3825);
DISPLAY INVISIBLE (-8100 3825);
FORCEPROP 1 LAST PATH I199
J 2
(-7773 3950);
DISPLAY 0.872340 (-7773 3950);
PAINT GREEN (-7773 3950);
DISPLAY INVISIBLE (-7773 3950);
FORCEADD TAP..1
R 2
(-7775 3900);
FORCEPROP 3 LASTPIN (-7725 3900) SIG_NAME M_D_CPU0_SA_CB<2>
J 0
(-7715 3910);
DISPLAY 0.659574 (-7715 3910);
PAINT MONO (-7715 3910);
DISPLAY INVISIBLE (-7715 3910);
FORCEPROP 1 LASTPIN (-7725 3900) BN 2
J 2
(-7713 3908);
DISPLAY 0.489362 (-7713 3908);
PAINT GREEN (-7713 3908);
FORCEPROP 2 LAST CDS_LIB mstr_standard
J 0
(-7775 3900);
DISPLAY 0.723404 (-7775 3900);
PAINT MONO (-7775 3900);
DISPLAY INVISIBLE (-7775 3900);
FORCEPROP 1 LAST BODY_TYPE PLUMBING
J 2
(-7775 3950);
DISPLAY 0.872340 (-7775 3950);
PAINT GREEN (-7775 3950);
DISPLAY INVISIBLE (-7775 3950);
FORCEPROP 1 LAST HDL_TAP TRUE
J 2
(-8100 3775);
DISPLAY 0.872340 (-8100 3775);
DISPLAY INVISIBLE (-8100 3775);
FORCEPROP 1 LAST PATH I200
J 2
(-7773 3900);
DISPLAY 0.872340 (-7773 3900);
PAINT GREEN (-7773 3900);
DISPLAY INVISIBLE (-7773 3900);
FORCEADD TAP..1
R 2
(-7775 4000);
FORCEPROP 3 LASTPIN (-7725 4000) SIG_NAME M_D_CPU0_SA_CB<4>
J 0
(-7715 4010);
DISPLAY 0.659574 (-7715 4010);
PAINT MONO (-7715 4010);
DISPLAY INVISIBLE (-7715 4010);
FORCEPROP 1 LASTPIN (-7725 4000) BN 4
J 2
(-7713 4008);
DISPLAY 0.489362 (-7713 4008);
PAINT GREEN (-7713 4008);
FORCEPROP 2 LAST CDS_LIB mstr_standard
J 0
(-7775 4000);
DISPLAY 0.723404 (-7775 4000);
PAINT MONO (-7775 4000);
DISPLAY INVISIBLE (-7775 4000);
FORCEPROP 1 LAST BODY_TYPE PLUMBING
J 2
(-7775 4050);
DISPLAY 0.872340 (-7775 4050);
PAINT GREEN (-7775 4050);
DISPLAY INVISIBLE (-7775 4050);
FORCEPROP 1 LAST HDL_TAP TRUE
J 2
(-8100 3875);
DISPLAY 0.872340 (-8100 3875);
DISPLAY INVISIBLE (-8100 3875);
FORCEPROP 1 LAST PATH I201
J 2
(-7773 4000);
DISPLAY 0.872340 (-7773 4000);
PAINT GREEN (-7773 4000);
DISPLAY INVISIBLE (-7773 4000);
FORCEADD TAP..1
R 2
(-7775 4050);
FORCEPROP 3 LASTPIN (-7725 4050) SIG_NAME M_D_CPU0_SA_CB<5>
J 0
(-7715 4060);
DISPLAY 0.659574 (-7715 4060);
PAINT MONO (-7715 4060);
DISPLAY INVISIBLE (-7715 4060);
FORCEPROP 1 LASTPIN (-7725 4050) BN 5
J 2
(-7713 4058);
DISPLAY 0.489362 (-7713 4058);
PAINT GREEN (-7713 4058);
FORCEPROP 2 LAST CDS_LIB mstr_standard
J 0
(-7775 4050);
DISPLAY 0.723404 (-7775 4050);
PAINT MONO (-7775 4050);
DISPLAY INVISIBLE (-7775 4050);
FORCEPROP 1 LAST BODY_TYPE PLUMBING
J 2
(-7775 4100);
DISPLAY 0.872340 (-7775 4100);
PAINT GREEN (-7775 4100);
DISPLAY INVISIBLE (-7775 4100);
FORCEPROP 1 LAST HDL_TAP TRUE
J 2
(-8100 3925);
DISPLAY 0.872340 (-8100 3925);
DISPLAY INVISIBLE (-8100 3925);
FORCEPROP 1 LAST PATH I202
J 2
(-7773 4050);
DISPLAY 0.872340 (-7773 4050);
PAINT GREEN (-7773 4050);
DISPLAY INVISIBLE (-7773 4050);
FORCEADD TAP..1
R 2
(-7775 4100);
FORCEPROP 3 LASTPIN (-7725 4100) SIG_NAME M_D_CPU0_SA_CB<6>
J 0
(-7715 4110);
DISPLAY 0.659574 (-7715 4110);
PAINT MONO (-7715 4110);
DISPLAY INVISIBLE (-7715 4110);
FORCEPROP 1 LASTPIN (-7725 4100) BN 6
J 2
(-7713 4108);
DISPLAY 0.489362 (-7713 4108);
PAINT GREEN (-7713 4108);
FORCEPROP 2 LAST CDS_LIB mstr_standard
J 0
(-7775 4100);
DISPLAY 0.723404 (-7775 4100);
PAINT MONO (-7775 4100);
DISPLAY INVISIBLE (-7775 4100);
FORCEPROP 1 LAST BODY_TYPE PLUMBING
J 2
(-7775 4150);
DISPLAY 0.872340 (-7775 4150);
PAINT GREEN (-7775 4150);
DISPLAY INVISIBLE (-7775 4150);
FORCEPROP 1 LAST HDL_TAP TRUE
J 2
(-8100 3975);
DISPLAY 0.872340 (-8100 3975);
DISPLAY INVISIBLE (-8100 3975);
FORCEPROP 1 LAST PATH I203
J 2
(-7773 4100);
DISPLAY 0.872340 (-7773 4100);
PAINT GREEN (-7773 4100);
DISPLAY INVISIBLE (-7773 4100);
FORCEADD TAP..1
(-6075 2350);
FORCEPROP 3 LASTPIN (-6125 2350) SIG_NAME M_D_CPU0_SB_DQ<0>
J 0
(-6115 2360);
DISPLAY 0.659574 (-6115 2360);
PAINT MONO (-6115 2360);
DISPLAY INVISIBLE (-6115 2360);
FORCEPROP 1 LASTPIN (-6125 2350) BN 0
J 0
(-6137 2358);
DISPLAY 0.489362 (-6137 2358);
PAINT GREEN (-6137 2358);
FORCEPROP 2 LAST CDS_LIB mstr_standard
J 0
(-6075 2350);
DISPLAY 0.723404 (-6075 2350);
PAINT MONO (-6075 2350);
DISPLAY INVISIBLE (-6075 2350);
FORCEPROP 1 LAST BODY_TYPE PLUMBING
J 0
(-6075 2400);
DISPLAY 0.872340 (-6075 2400);
PAINT GREEN (-6075 2400);
DISPLAY INVISIBLE (-6075 2400);
FORCEPROP 1 LAST HDL_TAP TRUE
J 0
(-5750 2225);
DISPLAY 0.872340 (-5750 2225);
DISPLAY INVISIBLE (-5750 2225);
FORCEPROP 1 LAST PATH I204
J 0
(-6077 2350);
DISPLAY 0.872340 (-6077 2350);
PAINT GREEN (-6077 2350);
DISPLAY INVISIBLE (-6077 2350);
FORCEADD TAP..1
(-6075 2400);
FORCEPROP 3 LASTPIN (-6125 2400) SIG_NAME M_D_CPU0_SB_DQ<1>
J 0
(-6115 2410);
DISPLAY 0.659574 (-6115 2410);
PAINT MONO (-6115 2410);
DISPLAY INVISIBLE (-6115 2410);
FORCEPROP 1 LASTPIN (-6125 2400) BN 1
J 0
(-6137 2408);
DISPLAY 0.489362 (-6137 2408);
PAINT GREEN (-6137 2408);
FORCEPROP 2 LAST CDS_LIB mstr_standard
J 0
(-6075 2400);
DISPLAY 0.723404 (-6075 2400);
PAINT MONO (-6075 2400);
DISPLAY INVISIBLE (-6075 2400);
FORCEPROP 1 LAST BODY_TYPE PLUMBING
J 0
(-6075 2450);
DISPLAY 0.872340 (-6075 2450);
PAINT GREEN (-6075 2450);
DISPLAY INVISIBLE (-6075 2450);
FORCEPROP 1 LAST HDL_TAP TRUE
J 0
(-5750 2275);
DISPLAY 0.872340 (-5750 2275);
DISPLAY INVISIBLE (-5750 2275);
FORCEPROP 1 LAST PATH I205
J 0
(-6077 2400);
DISPLAY 0.872340 (-6077 2400);
PAINT GREEN (-6077 2400);
DISPLAY INVISIBLE (-6077 2400);
FORCEADD TAP..1
(-6075 2450);
FORCEPROP 3 LASTPIN (-6125 2450) SIG_NAME M_D_CPU0_SB_DQ<2>
J 0
(-6115 2460);
DISPLAY 0.659574 (-6115 2460);
PAINT MONO (-6115 2460);
DISPLAY INVISIBLE (-6115 2460);
FORCEPROP 1 LASTPIN (-6125 2450) BN 2
J 0
(-6137 2458);
DISPLAY 0.489362 (-6137 2458);
PAINT GREEN (-6137 2458);
FORCEPROP 2 LAST CDS_LIB mstr_standard
J 0
(-6075 2450);
DISPLAY 0.723404 (-6075 2450);
PAINT MONO (-6075 2450);
DISPLAY INVISIBLE (-6075 2450);
FORCEPROP 1 LAST BODY_TYPE PLUMBING
J 0
(-6075 2500);
DISPLAY 0.872340 (-6075 2500);
PAINT GREEN (-6075 2500);
DISPLAY INVISIBLE (-6075 2500);
FORCEPROP 1 LAST HDL_TAP TRUE
J 0
(-5750 2325);
DISPLAY 0.872340 (-5750 2325);
DISPLAY INVISIBLE (-5750 2325);
FORCEPROP 1 LAST PATH I206
J 0
(-6077 2450);
DISPLAY 0.872340 (-6077 2450);
PAINT GREEN (-6077 2450);
DISPLAY INVISIBLE (-6077 2450);
FORCEADD TAP..1
(-6075 2500);
FORCEPROP 3 LASTPIN (-6125 2500) SIG_NAME M_D_CPU0_SB_DQ<3>
J 0
(-6115 2510);
DISPLAY 0.659574 (-6115 2510);
PAINT MONO (-6115 2510);
DISPLAY INVISIBLE (-6115 2510);
FORCEPROP 1 LASTPIN (-6125 2500) BN 3
J 0
(-6137 2508);
DISPLAY 0.489362 (-6137 2508);
PAINT GREEN (-6137 2508);
FORCEPROP 2 LAST CDS_LIB mstr_standard
J 0
(-6075 2500);
DISPLAY 0.723404 (-6075 2500);
PAINT MONO (-6075 2500);
DISPLAY INVISIBLE (-6075 2500);
FORCEPROP 1 LAST BODY_TYPE PLUMBING
J 0
(-6075 2550);
DISPLAY 0.872340 (-6075 2550);
PAINT GREEN (-6075 2550);
DISPLAY INVISIBLE (-6075 2550);
FORCEPROP 1 LAST HDL_TAP TRUE
J 0
(-5750 2375);
DISPLAY 0.872340 (-5750 2375);
DISPLAY INVISIBLE (-5750 2375);
FORCEPROP 1 LAST PATH I207
J 0
(-6077 2500);
DISPLAY 0.872340 (-6077 2500);
PAINT GREEN (-6077 2500);
DISPLAY INVISIBLE (-6077 2500);
FORCEADD TAP..1
(-6075 2550);
FORCEPROP 3 LASTPIN (-6125 2550) SIG_NAME M_D_CPU0_SB_DQ<4>
J 0
(-6115 2560);
DISPLAY 0.659574 (-6115 2560);
PAINT MONO (-6115 2560);
DISPLAY INVISIBLE (-6115 2560);
FORCEPROP 1 LASTPIN (-6125 2550) BN 4
J 0
(-6137 2558);
DISPLAY 0.489362 (-6137 2558);
PAINT GREEN (-6137 2558);
FORCEPROP 2 LAST CDS_LIB mstr_standard
J 0
(-6075 2550);
DISPLAY 0.723404 (-6075 2550);
PAINT MONO (-6075 2550);
DISPLAY INVISIBLE (-6075 2550);
FORCEPROP 1 LAST BODY_TYPE PLUMBING
J 0
(-6075 2600);
DISPLAY 0.872340 (-6075 2600);
PAINT GREEN (-6075 2600);
DISPLAY INVISIBLE (-6075 2600);
FORCEPROP 1 LAST HDL_TAP TRUE
J 0
(-5750 2425);
DISPLAY 0.872340 (-5750 2425);
DISPLAY INVISIBLE (-5750 2425);
FORCEPROP 1 LAST PATH I208
J 0
(-6077 2550);
DISPLAY 0.872340 (-6077 2550);
PAINT GREEN (-6077 2550);
DISPLAY INVISIBLE (-6077 2550);
FORCEADD TAP..1
(-6075 2600);
FORCEPROP 3 LASTPIN (-6125 2600) SIG_NAME M_D_CPU0_SB_DQ<5>
J 0
(-6115 2610);
DISPLAY 0.659574 (-6115 2610);
PAINT MONO (-6115 2610);
DISPLAY INVISIBLE (-6115 2610);
FORCEPROP 1 LASTPIN (-6125 2600) BN 5
J 0
(-6137 2608);
DISPLAY 0.489362 (-6137 2608);
PAINT GREEN (-6137 2608);
FORCEPROP 2 LAST CDS_LIB mstr_standard
J 0
(-6075 2600);
DISPLAY 0.723404 (-6075 2600);
PAINT MONO (-6075 2600);
DISPLAY INVISIBLE (-6075 2600);
FORCEPROP 1 LAST BODY_TYPE PLUMBING
J 0
(-6075 2650);
DISPLAY 0.872340 (-6075 2650);
PAINT GREEN (-6075 2650);
DISPLAY INVISIBLE (-6075 2650);
FORCEPROP 1 LAST HDL_TAP TRUE
J 0
(-5750 2475);
DISPLAY 0.872340 (-5750 2475);
DISPLAY INVISIBLE (-5750 2475);
FORCEPROP 1 LAST PATH I209
J 0
(-6077 2600);
DISPLAY 0.872340 (-6077 2600);
PAINT GREEN (-6077 2600);
DISPLAY INVISIBLE (-6077 2600);
FORCEADD TAP..1
(-6075 2700);
FORCEPROP 3 LASTPIN (-6125 2700) SIG_NAME M_D_CPU0_SB_DQ<7>
J 0
(-6115 2710);
DISPLAY 0.659574 (-6115 2710);
PAINT MONO (-6115 2710);
DISPLAY INVISIBLE (-6115 2710);
FORCEPROP 1 LASTPIN (-6125 2700) BN 7
J 0
(-6137 2708);
DISPLAY 0.489362 (-6137 2708);
PAINT GREEN (-6137 2708);
FORCEPROP 2 LAST CDS_LIB mstr_standard
J 0
(-6075 2700);
DISPLAY 0.723404 (-6075 2700);
PAINT MONO (-6075 2700);
DISPLAY INVISIBLE (-6075 2700);
FORCEPROP 1 LAST BODY_TYPE PLUMBING
J 0
(-6075 2750);
DISPLAY 0.872340 (-6075 2750);
PAINT GREEN (-6075 2750);
DISPLAY INVISIBLE (-6075 2750);
FORCEPROP 1 LAST HDL_TAP TRUE
J 0
(-5750 2575);
DISPLAY 0.872340 (-5750 2575);
DISPLAY INVISIBLE (-5750 2575);
FORCEPROP 1 LAST PATH I210
J 0
(-6077 2700);
DISPLAY 0.872340 (-6077 2700);
PAINT GREEN (-6077 2700);
DISPLAY INVISIBLE (-6077 2700);
FORCEADD TAP..1
(-6075 2650);
FORCEPROP 3 LASTPIN (-6125 2650) SIG_NAME M_D_CPU0_SB_DQ<6>
J 0
(-6115 2660);
DISPLAY 0.659574 (-6115 2660);
PAINT MONO (-6115 2660);
DISPLAY INVISIBLE (-6115 2660);
FORCEPROP 1 LASTPIN (-6125 2650) BN 6
J 0
(-6137 2658);
DISPLAY 0.489362 (-6137 2658);
PAINT GREEN (-6137 2658);
FORCEPROP 2 LAST CDS_LIB mstr_standard
J 0
(-6075 2650);
DISPLAY 0.723404 (-6075 2650);
PAINT MONO (-6075 2650);
DISPLAY INVISIBLE (-6075 2650);
FORCEPROP 1 LAST BODY_TYPE PLUMBING
J 0
(-6075 2700);
DISPLAY 0.872340 (-6075 2700);
PAINT GREEN (-6075 2700);
DISPLAY INVISIBLE (-6075 2700);
FORCEPROP 1 LAST HDL_TAP TRUE
J 0
(-5750 2525);
DISPLAY 0.872340 (-5750 2525);
DISPLAY INVISIBLE (-5750 2525);
FORCEPROP 1 LAST PATH I211
J 0
(-6077 2650);
DISPLAY 0.872340 (-6077 2650);
PAINT GREEN (-6077 2650);
DISPLAY INVISIBLE (-6077 2650);
FORCEADD TAP..1
(-6075 2750);
FORCEPROP 3 LASTPIN (-6125 2750) SIG_NAME M_D_CPU0_SB_DQ<8>
J 0
(-6115 2760);
DISPLAY 0.659574 (-6115 2760);
PAINT MONO (-6115 2760);
DISPLAY INVISIBLE (-6115 2760);
FORCEPROP 1 LASTPIN (-6125 2750) BN 8
J 0
(-6137 2758);
DISPLAY 0.489362 (-6137 2758);
PAINT GREEN (-6137 2758);
FORCEPROP 2 LAST CDS_LIB mstr_standard
J 0
(-6075 2750);
DISPLAY 0.723404 (-6075 2750);
PAINT MONO (-6075 2750);
DISPLAY INVISIBLE (-6075 2750);
FORCEPROP 1 LAST BODY_TYPE PLUMBING
J 0
(-6075 2800);
DISPLAY 0.872340 (-6075 2800);
PAINT GREEN (-6075 2800);
DISPLAY INVISIBLE (-6075 2800);
FORCEPROP 1 LAST HDL_TAP TRUE
J 0
(-5750 2625);
DISPLAY 0.872340 (-5750 2625);
DISPLAY INVISIBLE (-5750 2625);
FORCEPROP 1 LAST PATH I212
J 0
(-6077 2750);
DISPLAY 0.872340 (-6077 2750);
PAINT GREEN (-6077 2750);
DISPLAY INVISIBLE (-6077 2750);
FORCEADD TAP..1
(-6075 2800);
FORCEPROP 3 LASTPIN (-6125 2800) SIG_NAME M_D_CPU0_SB_DQ<9>
J 0
(-6115 2810);
DISPLAY 0.659574 (-6115 2810);
PAINT MONO (-6115 2810);
DISPLAY INVISIBLE (-6115 2810);
FORCEPROP 1 LASTPIN (-6125 2800) BN 9
J 0
(-6137 2808);
DISPLAY 0.489362 (-6137 2808);
PAINT GREEN (-6137 2808);
FORCEPROP 2 LAST CDS_LIB mstr_standard
J 0
(-6075 2800);
DISPLAY 0.723404 (-6075 2800);
PAINT MONO (-6075 2800);
DISPLAY INVISIBLE (-6075 2800);
FORCEPROP 1 LAST BODY_TYPE PLUMBING
J 0
(-6075 2850);
DISPLAY 0.872340 (-6075 2850);
PAINT GREEN (-6075 2850);
DISPLAY INVISIBLE (-6075 2850);
FORCEPROP 1 LAST HDL_TAP TRUE
J 0
(-5750 2675);
DISPLAY 0.872340 (-5750 2675);
DISPLAY INVISIBLE (-5750 2675);
FORCEPROP 1 LAST PATH I213
J 0
(-6077 2800);
DISPLAY 0.872340 (-6077 2800);
PAINT GREEN (-6077 2800);
DISPLAY INVISIBLE (-6077 2800);
FORCEADD TAP..1
(-6075 2850);
FORCEPROP 3 LASTPIN (-6125 2850) SIG_NAME M_D_CPU0_SB_DQ<10>
J 0
(-6115 2860);
DISPLAY 0.659574 (-6115 2860);
PAINT MONO (-6115 2860);
DISPLAY INVISIBLE (-6115 2860);
FORCEPROP 1 LASTPIN (-6125 2850) BN 10
J 0
(-6137 2858);
DISPLAY 0.489362 (-6137 2858);
PAINT GREEN (-6137 2858);
FORCEPROP 2 LAST CDS_LIB mstr_standard
J 0
(-6075 2850);
DISPLAY 0.723404 (-6075 2850);
PAINT MONO (-6075 2850);
DISPLAY INVISIBLE (-6075 2850);
FORCEPROP 1 LAST BODY_TYPE PLUMBING
J 0
(-6075 2900);
DISPLAY 0.872340 (-6075 2900);
PAINT GREEN (-6075 2900);
DISPLAY INVISIBLE (-6075 2900);
FORCEPROP 1 LAST HDL_TAP TRUE
J 0
(-5750 2725);
DISPLAY 0.872340 (-5750 2725);
DISPLAY INVISIBLE (-5750 2725);
FORCEPROP 1 LAST PATH I214
J 0
(-6077 2850);
DISPLAY 0.872340 (-6077 2850);
PAINT GREEN (-6077 2850);
DISPLAY INVISIBLE (-6077 2850);
FORCEADD TAP..1
(-6075 2950);
FORCEPROP 3 LASTPIN (-6125 2950) SIG_NAME M_D_CPU0_SB_DQ<12>
J 0
(-6115 2960);
DISPLAY 0.659574 (-6115 2960);
PAINT MONO (-6115 2960);
DISPLAY INVISIBLE (-6115 2960);
FORCEPROP 1 LASTPIN (-6125 2950) BN 12
J 0
(-6137 2958);
DISPLAY 0.489362 (-6137 2958);
PAINT GREEN (-6137 2958);
FORCEPROP 2 LAST CDS_LIB mstr_standard
J 0
(-6075 2950);
DISPLAY 0.723404 (-6075 2950);
PAINT MONO (-6075 2950);
DISPLAY INVISIBLE (-6075 2950);
FORCEPROP 1 LAST BODY_TYPE PLUMBING
J 0
(-6075 3000);
DISPLAY 0.872340 (-6075 3000);
PAINT GREEN (-6075 3000);
DISPLAY INVISIBLE (-6075 3000);
FORCEPROP 1 LAST HDL_TAP TRUE
J 0
(-5750 2825);
DISPLAY 0.872340 (-5750 2825);
DISPLAY INVISIBLE (-5750 2825);
FORCEPROP 1 LAST PATH I215
J 0
(-6077 2950);
DISPLAY 0.872340 (-6077 2950);
PAINT GREEN (-6077 2950);
DISPLAY INVISIBLE (-6077 2950);
FORCEADD TAP..1
(-6075 2900);
FORCEPROP 3 LASTPIN (-6125 2900) SIG_NAME M_D_CPU0_SB_DQ<11>
J 0
(-6115 2910);
DISPLAY 0.659574 (-6115 2910);
PAINT MONO (-6115 2910);
DISPLAY INVISIBLE (-6115 2910);
FORCEPROP 1 LASTPIN (-6125 2900) BN 11
J 0
(-6137 2908);
DISPLAY 0.489362 (-6137 2908);
PAINT GREEN (-6137 2908);
FORCEPROP 2 LAST CDS_LIB mstr_standard
J 0
(-6075 2900);
DISPLAY 0.723404 (-6075 2900);
PAINT MONO (-6075 2900);
DISPLAY INVISIBLE (-6075 2900);
FORCEPROP 1 LAST BODY_TYPE PLUMBING
J 0
(-6075 2950);
DISPLAY 0.872340 (-6075 2950);
PAINT GREEN (-6075 2950);
DISPLAY INVISIBLE (-6075 2950);
FORCEPROP 1 LAST HDL_TAP TRUE
J 0
(-5750 2775);
DISPLAY 0.872340 (-5750 2775);
DISPLAY INVISIBLE (-5750 2775);
FORCEPROP 1 LAST PATH I216
J 0
(-6077 2900);
DISPLAY 0.872340 (-6077 2900);
PAINT GREEN (-6077 2900);
DISPLAY INVISIBLE (-6077 2900);
FORCEADD TAP..1
(-6075 3100);
FORCEPROP 3 LASTPIN (-6125 3100) SIG_NAME M_D_CPU0_SB_DQ<15>
J 0
(-6115 3110);
DISPLAY 0.659574 (-6115 3110);
PAINT MONO (-6115 3110);
DISPLAY INVISIBLE (-6115 3110);
FORCEPROP 1 LASTPIN (-6125 3100) BN 15
J 0
(-6137 3108);
DISPLAY 0.489362 (-6137 3108);
PAINT GREEN (-6137 3108);
FORCEPROP 2 LAST CDS_LIB mstr_standard
J 0
(-6075 3100);
DISPLAY 0.723404 (-6075 3100);
PAINT MONO (-6075 3100);
DISPLAY INVISIBLE (-6075 3100);
FORCEPROP 1 LAST BODY_TYPE PLUMBING
J 0
(-6075 3150);
DISPLAY 0.872340 (-6075 3150);
PAINT GREEN (-6075 3150);
DISPLAY INVISIBLE (-6075 3150);
FORCEPROP 1 LAST HDL_TAP TRUE
J 0
(-5750 2975);
DISPLAY 0.872340 (-5750 2975);
DISPLAY INVISIBLE (-5750 2975);
FORCEPROP 1 LAST PATH I217
J 0
(-6077 3100);
DISPLAY 0.872340 (-6077 3100);
PAINT GREEN (-6077 3100);
DISPLAY INVISIBLE (-6077 3100);
FORCEADD TAP..1
(-6075 3050);
FORCEPROP 3 LASTPIN (-6125 3050) SIG_NAME M_D_CPU0_SB_DQ<14>
J 0
(-6115 3060);
DISPLAY 0.659574 (-6115 3060);
PAINT MONO (-6115 3060);
DISPLAY INVISIBLE (-6115 3060);
FORCEPROP 1 LASTPIN (-6125 3050) BN 14
J 0
(-6137 3058);
DISPLAY 0.489362 (-6137 3058);
PAINT GREEN (-6137 3058);
FORCEPROP 2 LAST CDS_LIB mstr_standard
J 0
(-6075 3050);
DISPLAY 0.723404 (-6075 3050);
PAINT MONO (-6075 3050);
DISPLAY INVISIBLE (-6075 3050);
FORCEPROP 1 LAST BODY_TYPE PLUMBING
J 0
(-6075 3100);
DISPLAY 0.872340 (-6075 3100);
PAINT GREEN (-6075 3100);
DISPLAY INVISIBLE (-6075 3100);
FORCEPROP 1 LAST HDL_TAP TRUE
J 0
(-5750 2925);
DISPLAY 0.872340 (-5750 2925);
DISPLAY INVISIBLE (-5750 2925);
FORCEPROP 1 LAST PATH I218
J 0
(-6077 3050);
DISPLAY 0.872340 (-6077 3050);
PAINT GREEN (-6077 3050);
DISPLAY INVISIBLE (-6077 3050);
FORCEADD TAP..1
(-6075 3000);
FORCEPROP 3 LASTPIN (-6125 3000) SIG_NAME M_D_CPU0_SB_DQ<13>
J 0
(-6115 3010);
DISPLAY 0.659574 (-6115 3010);
PAINT MONO (-6115 3010);
DISPLAY INVISIBLE (-6115 3010);
FORCEPROP 1 LASTPIN (-6125 3000) BN 13
J 0
(-6137 3008);
DISPLAY 0.489362 (-6137 3008);
PAINT GREEN (-6137 3008);
FORCEPROP 2 LAST CDS_LIB mstr_standard
J 0
(-6075 3000);
DISPLAY 0.723404 (-6075 3000);
PAINT MONO (-6075 3000);
DISPLAY INVISIBLE (-6075 3000);
FORCEPROP 1 LAST BODY_TYPE PLUMBING
J 0
(-6075 3050);
DISPLAY 0.872340 (-6075 3050);
PAINT GREEN (-6075 3050);
DISPLAY INVISIBLE (-6075 3050);
FORCEPROP 1 LAST HDL_TAP TRUE
J 0
(-5750 2875);
DISPLAY 0.872340 (-5750 2875);
DISPLAY INVISIBLE (-5750 2875);
FORCEPROP 1 LAST PATH I219
J 0
(-6077 3000);
DISPLAY 0.872340 (-6077 3000);
PAINT GREEN (-6077 3000);
DISPLAY INVISIBLE (-6077 3000);
FORCEADD TAP..1
(-6075 3250);
FORCEPROP 3 LASTPIN (-6125 3250) SIG_NAME M_D_CPU0_SB_DQ<18>
J 0
(-6115 3260);
DISPLAY 0.659574 (-6115 3260);
PAINT MONO (-6115 3260);
DISPLAY INVISIBLE (-6115 3260);
FORCEPROP 1 LASTPIN (-6125 3250) BN 18
J 0
(-6137 3258);
DISPLAY 0.489362 (-6137 3258);
PAINT GREEN (-6137 3258);
FORCEPROP 2 LAST CDS_LIB mstr_standard
J 0
(-6075 3250);
DISPLAY 0.723404 (-6075 3250);
PAINT MONO (-6075 3250);
DISPLAY INVISIBLE (-6075 3250);
FORCEPROP 1 LAST BODY_TYPE PLUMBING
J 0
(-6075 3300);
DISPLAY 0.872340 (-6075 3300);
PAINT GREEN (-6075 3300);
DISPLAY INVISIBLE (-6075 3300);
FORCEPROP 1 LAST HDL_TAP TRUE
J 0
(-5750 3125);
DISPLAY 0.872340 (-5750 3125);
DISPLAY INVISIBLE (-5750 3125);
FORCEPROP 1 LAST PATH I220
J 0
(-6077 3250);
DISPLAY 0.872340 (-6077 3250);
PAINT GREEN (-6077 3250);
DISPLAY INVISIBLE (-6077 3250);
FORCEADD TAP..1
(-6075 3200);
FORCEPROP 3 LASTPIN (-6125 3200) SIG_NAME M_D_CPU0_SB_DQ<17>
J 0
(-6115 3210);
DISPLAY 0.659574 (-6115 3210);
PAINT MONO (-6115 3210);
DISPLAY INVISIBLE (-6115 3210);
FORCEPROP 1 LASTPIN (-6125 3200) BN 17
J 0
(-6137 3208);
DISPLAY 0.489362 (-6137 3208);
PAINT GREEN (-6137 3208);
FORCEPROP 2 LAST CDS_LIB mstr_standard
J 0
(-6075 3200);
DISPLAY 0.723404 (-6075 3200);
PAINT MONO (-6075 3200);
DISPLAY INVISIBLE (-6075 3200);
FORCEPROP 1 LAST BODY_TYPE PLUMBING
J 0
(-6075 3250);
DISPLAY 0.872340 (-6075 3250);
PAINT GREEN (-6075 3250);
DISPLAY INVISIBLE (-6075 3250);
FORCEPROP 1 LAST HDL_TAP TRUE
J 0
(-5750 3075);
DISPLAY 0.872340 (-5750 3075);
DISPLAY INVISIBLE (-5750 3075);
FORCEPROP 1 LAST PATH I221
J 0
(-6077 3200);
DISPLAY 0.872340 (-6077 3200);
PAINT GREEN (-6077 3200);
DISPLAY INVISIBLE (-6077 3200);
FORCEADD TAP..1
(-6075 3150);
FORCEPROP 3 LASTPIN (-6125 3150) SIG_NAME M_D_CPU0_SB_DQ<16>
J 0
(-6115 3160);
DISPLAY 0.659574 (-6115 3160);
PAINT MONO (-6115 3160);
DISPLAY INVISIBLE (-6115 3160);
FORCEPROP 1 LASTPIN (-6125 3150) BN 16
J 0
(-6137 3158);
DISPLAY 0.489362 (-6137 3158);
PAINT GREEN (-6137 3158);
FORCEPROP 2 LAST CDS_LIB mstr_standard
J 0
(-6075 3150);
DISPLAY 0.723404 (-6075 3150);
PAINT MONO (-6075 3150);
DISPLAY INVISIBLE (-6075 3150);
FORCEPROP 1 LAST BODY_TYPE PLUMBING
J 0
(-6075 3200);
DISPLAY 0.872340 (-6075 3200);
PAINT GREEN (-6075 3200);
DISPLAY INVISIBLE (-6075 3200);
FORCEPROP 1 LAST HDL_TAP TRUE
J 0
(-5750 3025);
DISPLAY 0.872340 (-5750 3025);
DISPLAY INVISIBLE (-5750 3025);
FORCEPROP 1 LAST PATH I222
J 0
(-6077 3150);
DISPLAY 0.872340 (-6077 3150);
PAINT GREEN (-6077 3150);
DISPLAY INVISIBLE (-6077 3150);
FORCEADD TAP..1
(-6075 3350);
FORCEPROP 3 LASTPIN (-6125 3350) SIG_NAME M_D_CPU0_SB_DQ<20>
J 0
(-6115 3360);
DISPLAY 0.659574 (-6115 3360);
PAINT MONO (-6115 3360);
DISPLAY INVISIBLE (-6115 3360);
FORCEPROP 1 LASTPIN (-6125 3350) BN 20
J 0
(-6137 3358);
DISPLAY 0.489362 (-6137 3358);
PAINT GREEN (-6137 3358);
FORCEPROP 2 LAST CDS_LIB mstr_standard
J 0
(-6075 3350);
DISPLAY 0.723404 (-6075 3350);
PAINT MONO (-6075 3350);
DISPLAY INVISIBLE (-6075 3350);
FORCEPROP 1 LAST BODY_TYPE PLUMBING
J 0
(-6075 3400);
DISPLAY 0.872340 (-6075 3400);
PAINT GREEN (-6075 3400);
DISPLAY INVISIBLE (-6075 3400);
FORCEPROP 1 LAST HDL_TAP TRUE
J 0
(-5750 3225);
DISPLAY 0.872340 (-5750 3225);
DISPLAY INVISIBLE (-5750 3225);
FORCEPROP 1 LAST PATH I223
J 0
(-6077 3350);
DISPLAY 0.872340 (-6077 3350);
PAINT GREEN (-6077 3350);
DISPLAY INVISIBLE (-6077 3350);
FORCEADD TAP..1
(-6075 3300);
FORCEPROP 3 LASTPIN (-6125 3300) SIG_NAME M_D_CPU0_SB_DQ<19>
J 0
(-6115 3310);
DISPLAY 0.659574 (-6115 3310);
PAINT MONO (-6115 3310);
DISPLAY INVISIBLE (-6115 3310);
FORCEPROP 1 LASTPIN (-6125 3300) BN 19
J 0
(-6137 3308);
DISPLAY 0.489362 (-6137 3308);
PAINT GREEN (-6137 3308);
FORCEPROP 2 LAST CDS_LIB mstr_standard
J 0
(-6075 3300);
DISPLAY 0.723404 (-6075 3300);
PAINT MONO (-6075 3300);
DISPLAY INVISIBLE (-6075 3300);
FORCEPROP 1 LAST BODY_TYPE PLUMBING
J 0
(-6075 3350);
DISPLAY 0.872340 (-6075 3350);
PAINT GREEN (-6075 3350);
DISPLAY INVISIBLE (-6075 3350);
FORCEPROP 1 LAST HDL_TAP TRUE
J 0
(-5750 3175);
DISPLAY 0.872340 (-5750 3175);
DISPLAY INVISIBLE (-5750 3175);
FORCEPROP 1 LAST PATH I224
J 0
(-6077 3300);
DISPLAY 0.872340 (-6077 3300);
PAINT GREEN (-6077 3300);
DISPLAY INVISIBLE (-6077 3300);
FORCEADD TAP..1
(-6075 3400);
FORCEPROP 3 LASTPIN (-6125 3400) SIG_NAME M_D_CPU0_SB_DQ<21>
J 0
(-6115 3410);
DISPLAY 0.659574 (-6115 3410);
PAINT MONO (-6115 3410);
DISPLAY INVISIBLE (-6115 3410);
FORCEPROP 1 LASTPIN (-6125 3400) BN 21
J 0
(-6137 3408);
DISPLAY 0.489362 (-6137 3408);
PAINT GREEN (-6137 3408);
FORCEPROP 2 LAST CDS_LIB mstr_standard
J 0
(-6075 3400);
DISPLAY 0.723404 (-6075 3400);
PAINT MONO (-6075 3400);
DISPLAY INVISIBLE (-6075 3400);
FORCEPROP 1 LAST BODY_TYPE PLUMBING
J 0
(-6075 3450);
DISPLAY 0.872340 (-6075 3450);
PAINT GREEN (-6075 3450);
DISPLAY INVISIBLE (-6075 3450);
FORCEPROP 1 LAST HDL_TAP TRUE
J 0
(-5750 3275);
DISPLAY 0.872340 (-5750 3275);
DISPLAY INVISIBLE (-5750 3275);
FORCEPROP 1 LAST PATH I225
J 0
(-6077 3400);
DISPLAY 0.872340 (-6077 3400);
PAINT GREEN (-6077 3400);
DISPLAY INVISIBLE (-6077 3400);
FORCEADD TAP..1
(-6075 3450);
FORCEPROP 3 LASTPIN (-6125 3450) SIG_NAME M_D_CPU0_SB_DQ<22>
J 0
(-6115 3460);
DISPLAY 0.659574 (-6115 3460);
PAINT MONO (-6115 3460);
DISPLAY INVISIBLE (-6115 3460);
FORCEPROP 1 LASTPIN (-6125 3450) BN 22
J 0
(-6137 3458);
DISPLAY 0.489362 (-6137 3458);
PAINT GREEN (-6137 3458);
FORCEPROP 2 LAST CDS_LIB mstr_standard
J 0
(-6075 3450);
DISPLAY 0.723404 (-6075 3450);
PAINT MONO (-6075 3450);
DISPLAY INVISIBLE (-6075 3450);
FORCEPROP 1 LAST BODY_TYPE PLUMBING
J 0
(-6075 3500);
DISPLAY 0.872340 (-6075 3500);
PAINT GREEN (-6075 3500);
DISPLAY INVISIBLE (-6075 3500);
FORCEPROP 1 LAST HDL_TAP TRUE
J 0
(-5750 3325);
DISPLAY 0.872340 (-5750 3325);
DISPLAY INVISIBLE (-5750 3325);
FORCEPROP 1 LAST PATH I226
J 0
(-6077 3450);
DISPLAY 0.872340 (-6077 3450);
PAINT GREEN (-6077 3450);
DISPLAY INVISIBLE (-6077 3450);
FORCEADD TAP..1
(-6075 3500);
FORCEPROP 3 LASTPIN (-6125 3500) SIG_NAME M_D_CPU0_SB_DQ<23>
J 0
(-6115 3510);
DISPLAY 0.659574 (-6115 3510);
PAINT MONO (-6115 3510);
DISPLAY INVISIBLE (-6115 3510);
FORCEPROP 1 LASTPIN (-6125 3500) BN 23
J 0
(-6137 3508);
DISPLAY 0.489362 (-6137 3508);
PAINT GREEN (-6137 3508);
FORCEPROP 2 LAST CDS_LIB mstr_standard
J 0
(-6075 3500);
DISPLAY 0.723404 (-6075 3500);
PAINT MONO (-6075 3500);
DISPLAY INVISIBLE (-6075 3500);
FORCEPROP 1 LAST BODY_TYPE PLUMBING
J 0
(-6075 3550);
DISPLAY 0.872340 (-6075 3550);
PAINT GREEN (-6075 3550);
DISPLAY INVISIBLE (-6075 3550);
FORCEPROP 1 LAST HDL_TAP TRUE
J 0
(-5750 3375);
DISPLAY 0.872340 (-5750 3375);
DISPLAY INVISIBLE (-5750 3375);
FORCEPROP 1 LAST PATH I227
J 0
(-6077 3500);
DISPLAY 0.872340 (-6077 3500);
PAINT GREEN (-6077 3500);
DISPLAY INVISIBLE (-6077 3500);
FORCEADD TAP..1
(-6075 3550);
FORCEPROP 3 LASTPIN (-6125 3550) SIG_NAME M_D_CPU0_SB_DQ<24>
J 0
(-6115 3560);
DISPLAY 0.659574 (-6115 3560);
PAINT MONO (-6115 3560);
DISPLAY INVISIBLE (-6115 3560);
FORCEPROP 1 LASTPIN (-6125 3550) BN 24
J 0
(-6137 3558);
DISPLAY 0.489362 (-6137 3558);
PAINT GREEN (-6137 3558);
FORCEPROP 2 LAST CDS_LIB mstr_standard
J 0
(-6075 3550);
DISPLAY 0.723404 (-6075 3550);
PAINT MONO (-6075 3550);
DISPLAY INVISIBLE (-6075 3550);
FORCEPROP 1 LAST BODY_TYPE PLUMBING
J 0
(-6075 3600);
DISPLAY 0.872340 (-6075 3600);
PAINT GREEN (-6075 3600);
DISPLAY INVISIBLE (-6075 3600);
FORCEPROP 1 LAST HDL_TAP TRUE
J 0
(-5750 3425);
DISPLAY 0.872340 (-5750 3425);
DISPLAY INVISIBLE (-5750 3425);
FORCEPROP 1 LAST PATH I228
J 0
(-6077 3550);
DISPLAY 0.872340 (-6077 3550);
PAINT GREEN (-6077 3550);
DISPLAY INVISIBLE (-6077 3550);
FORCEADD TAP..1
(-6075 3600);
FORCEPROP 3 LASTPIN (-6125 3600) SIG_NAME M_D_CPU0_SB_DQ<25>
J 0
(-6115 3610);
DISPLAY 0.659574 (-6115 3610);
PAINT MONO (-6115 3610);
DISPLAY INVISIBLE (-6115 3610);
FORCEPROP 1 LASTPIN (-6125 3600) BN 25
J 0
(-6137 3608);
DISPLAY 0.489362 (-6137 3608);
PAINT GREEN (-6137 3608);
FORCEPROP 2 LAST CDS_LIB mstr_standard
J 0
(-6075 3600);
DISPLAY 0.723404 (-6075 3600);
PAINT MONO (-6075 3600);
DISPLAY INVISIBLE (-6075 3600);
FORCEPROP 1 LAST BODY_TYPE PLUMBING
J 0
(-6075 3650);
DISPLAY 0.872340 (-6075 3650);
PAINT GREEN (-6075 3650);
DISPLAY INVISIBLE (-6075 3650);
FORCEPROP 1 LAST HDL_TAP TRUE
J 0
(-5750 3475);
DISPLAY 0.872340 (-5750 3475);
DISPLAY INVISIBLE (-5750 3475);
FORCEPROP 1 LAST PATH I229
J 0
(-6077 3600);
DISPLAY 0.872340 (-6077 3600);
PAINT GREEN (-6077 3600);
DISPLAY INVISIBLE (-6077 3600);
FORCEADD TAP..1
(-6075 3650);
FORCEPROP 3 LASTPIN (-6125 3650) SIG_NAME M_D_CPU0_SB_DQ<26>
J 0
(-6115 3660);
DISPLAY 0.659574 (-6115 3660);
PAINT MONO (-6115 3660);
DISPLAY INVISIBLE (-6115 3660);
FORCEPROP 1 LASTPIN (-6125 3650) BN 26
J 0
(-6137 3658);
DISPLAY 0.489362 (-6137 3658);
PAINT GREEN (-6137 3658);
FORCEPROP 2 LAST CDS_LIB mstr_standard
J 0
(-6075 3650);
DISPLAY 0.723404 (-6075 3650);
PAINT MONO (-6075 3650);
DISPLAY INVISIBLE (-6075 3650);
FORCEPROP 1 LAST BODY_TYPE PLUMBING
J 0
(-6075 3700);
DISPLAY 0.872340 (-6075 3700);
PAINT GREEN (-6075 3700);
DISPLAY INVISIBLE (-6075 3700);
FORCEPROP 1 LAST HDL_TAP TRUE
J 0
(-5750 3525);
DISPLAY 0.872340 (-5750 3525);
DISPLAY INVISIBLE (-5750 3525);
FORCEPROP 1 LAST PATH I230
J 0
(-6077 3650);
DISPLAY 0.872340 (-6077 3650);
PAINT GREEN (-6077 3650);
DISPLAY INVISIBLE (-6077 3650);
FORCEADD TAP..1
(-6075 3700);
FORCEPROP 3 LASTPIN (-6125 3700) SIG_NAME M_D_CPU0_SB_DQ<27>
J 0
(-6115 3710);
DISPLAY 0.659574 (-6115 3710);
PAINT MONO (-6115 3710);
DISPLAY INVISIBLE (-6115 3710);
FORCEPROP 1 LASTPIN (-6125 3700) BN 27
J 0
(-6137 3708);
DISPLAY 0.489362 (-6137 3708);
PAINT GREEN (-6137 3708);
FORCEPROP 2 LAST CDS_LIB mstr_standard
J 0
(-6075 3700);
DISPLAY 0.723404 (-6075 3700);
PAINT MONO (-6075 3700);
DISPLAY INVISIBLE (-6075 3700);
FORCEPROP 1 LAST BODY_TYPE PLUMBING
J 0
(-6075 3750);
DISPLAY 0.872340 (-6075 3750);
PAINT GREEN (-6075 3750);
DISPLAY INVISIBLE (-6075 3750);
FORCEPROP 1 LAST HDL_TAP TRUE
J 0
(-5750 3575);
DISPLAY 0.872340 (-5750 3575);
DISPLAY INVISIBLE (-5750 3575);
FORCEPROP 1 LAST PATH I231
J 0
(-6077 3700);
DISPLAY 0.872340 (-6077 3700);
PAINT GREEN (-6077 3700);
DISPLAY INVISIBLE (-6077 3700);
FORCEADD TAP..1
(-6075 3750);
FORCEPROP 3 LASTPIN (-6125 3750) SIG_NAME M_D_CPU0_SB_DQ<28>
J 0
(-6115 3760);
DISPLAY 0.659574 (-6115 3760);
PAINT MONO (-6115 3760);
DISPLAY INVISIBLE (-6115 3760);
FORCEPROP 1 LASTPIN (-6125 3750) BN 28
J 0
(-6137 3758);
DISPLAY 0.489362 (-6137 3758);
PAINT GREEN (-6137 3758);
FORCEPROP 2 LAST CDS_LIB mstr_standard
J 0
(-6075 3750);
DISPLAY 0.723404 (-6075 3750);
PAINT MONO (-6075 3750);
DISPLAY INVISIBLE (-6075 3750);
FORCEPROP 1 LAST BODY_TYPE PLUMBING
J 0
(-6075 3800);
DISPLAY 0.872340 (-6075 3800);
PAINT GREEN (-6075 3800);
DISPLAY INVISIBLE (-6075 3800);
FORCEPROP 1 LAST HDL_TAP TRUE
J 0
(-5750 3625);
DISPLAY 0.872340 (-5750 3625);
DISPLAY INVISIBLE (-5750 3625);
FORCEPROP 1 LAST PATH I232
J 0
(-6077 3750);
DISPLAY 0.872340 (-6077 3750);
PAINT GREEN (-6077 3750);
DISPLAY INVISIBLE (-6077 3750);
FORCEADD TAP..1
(-6075 3800);
FORCEPROP 3 LASTPIN (-6125 3800) SIG_NAME M_D_CPU0_SB_DQ<29>
J 0
(-6115 3810);
DISPLAY 0.659574 (-6115 3810);
PAINT MONO (-6115 3810);
DISPLAY INVISIBLE (-6115 3810);
FORCEPROP 1 LASTPIN (-6125 3800) BN 29
J 0
(-6137 3808);
DISPLAY 0.489362 (-6137 3808);
PAINT GREEN (-6137 3808);
FORCEPROP 2 LAST CDS_LIB mstr_standard
J 0
(-6075 3800);
DISPLAY 0.723404 (-6075 3800);
PAINT MONO (-6075 3800);
DISPLAY INVISIBLE (-6075 3800);
FORCEPROP 1 LAST BODY_TYPE PLUMBING
J 0
(-6075 3850);
DISPLAY 0.872340 (-6075 3850);
PAINT GREEN (-6075 3850);
DISPLAY INVISIBLE (-6075 3850);
FORCEPROP 1 LAST HDL_TAP TRUE
J 0
(-5750 3675);
DISPLAY 0.872340 (-5750 3675);
DISPLAY INVISIBLE (-5750 3675);
FORCEPROP 1 LAST PATH I233
J 0
(-6077 3800);
DISPLAY 0.872340 (-6077 3800);
PAINT GREEN (-6077 3800);
DISPLAY INVISIBLE (-6077 3800);
FORCEADD TAP..1
(-6075 3850);
FORCEPROP 3 LASTPIN (-6125 3850) SIG_NAME M_D_CPU0_SB_DQ<30>
J 0
(-6115 3860);
DISPLAY 0.659574 (-6115 3860);
PAINT MONO (-6115 3860);
DISPLAY INVISIBLE (-6115 3860);
FORCEPROP 1 LASTPIN (-6125 3850) BN 30
J 0
(-6137 3858);
DISPLAY 0.489362 (-6137 3858);
PAINT GREEN (-6137 3858);
FORCEPROP 2 LAST CDS_LIB mstr_standard
J 0
(-6075 3850);
DISPLAY 0.723404 (-6075 3850);
PAINT MONO (-6075 3850);
DISPLAY INVISIBLE (-6075 3850);
FORCEPROP 1 LAST BODY_TYPE PLUMBING
J 0
(-6075 3900);
DISPLAY 0.872340 (-6075 3900);
PAINT GREEN (-6075 3900);
DISPLAY INVISIBLE (-6075 3900);
FORCEPROP 1 LAST HDL_TAP TRUE
J 0
(-5750 3725);
DISPLAY 0.872340 (-5750 3725);
DISPLAY INVISIBLE (-5750 3725);
FORCEPROP 1 LAST PATH I234
J 0
(-6077 3850);
DISPLAY 0.872340 (-6077 3850);
PAINT GREEN (-6077 3850);
DISPLAY INVISIBLE (-6077 3850);
FORCEADD TAP..1
(-6075 4000);
FORCEPROP 3 LASTPIN (-6125 4000) SIG_NAME M_D_CPU0_SA_DQ<0>
J 0
(-6115 4010);
DISPLAY 0.659574 (-6115 4010);
PAINT MONO (-6115 4010);
DISPLAY INVISIBLE (-6115 4010);
FORCEPROP 1 LASTPIN (-6125 4000) BN 0
J 0
(-6137 4008);
DISPLAY 0.489362 (-6137 4008);
PAINT GREEN (-6137 4008);
FORCEPROP 2 LAST CDS_LIB mstr_standard
J 0
(-6075 4000);
DISPLAY 0.723404 (-6075 4000);
PAINT MONO (-6075 4000);
DISPLAY INVISIBLE (-6075 4000);
FORCEPROP 1 LAST BODY_TYPE PLUMBING
J 0
(-6075 4050);
DISPLAY 0.872340 (-6075 4050);
PAINT GREEN (-6075 4050);
DISPLAY INVISIBLE (-6075 4050);
FORCEPROP 1 LAST HDL_TAP TRUE
J 0
(-5750 3875);
DISPLAY 0.872340 (-5750 3875);
DISPLAY INVISIBLE (-5750 3875);
FORCEPROP 1 LAST PATH I235
J 0
(-6077 4000);
DISPLAY 0.872340 (-6077 4000);
PAINT GREEN (-6077 4000);
DISPLAY INVISIBLE (-6077 4000);
FORCEADD TAP..1
(-6075 3900);
FORCEPROP 3 LASTPIN (-6125 3900) SIG_NAME M_D_CPU0_SB_DQ<31>
J 0
(-6115 3910);
DISPLAY 0.659574 (-6115 3910);
PAINT MONO (-6115 3910);
DISPLAY INVISIBLE (-6115 3910);
FORCEPROP 1 LASTPIN (-6125 3900) BN 31
J 0
(-6137 3908);
DISPLAY 0.489362 (-6137 3908);
PAINT GREEN (-6137 3908);
FORCEPROP 2 LAST CDS_LIB mstr_standard
J 0
(-6075 3900);
DISPLAY 0.723404 (-6075 3900);
PAINT MONO (-6075 3900);
DISPLAY INVISIBLE (-6075 3900);
FORCEPROP 1 LAST BODY_TYPE PLUMBING
J 0
(-6075 3950);
DISPLAY 0.872340 (-6075 3950);
PAINT GREEN (-6075 3950);
DISPLAY INVISIBLE (-6075 3950);
FORCEPROP 1 LAST HDL_TAP TRUE
J 0
(-5750 3775);
DISPLAY 0.872340 (-5750 3775);
DISPLAY INVISIBLE (-5750 3775);
FORCEPROP 1 LAST PATH I236
J 0
(-6077 3900);
DISPLAY 0.872340 (-6077 3900);
PAINT GREEN (-6077 3900);
DISPLAY INVISIBLE (-6077 3900);
FORCEADD TAP..1
(-6075 4050);
FORCEPROP 3 LASTPIN (-6125 4050) SIG_NAME M_D_CPU0_SA_DQ<1>
J 0
(-6115 4060);
DISPLAY 0.659574 (-6115 4060);
PAINT MONO (-6115 4060);
DISPLAY INVISIBLE (-6115 4060);
FORCEPROP 1 LASTPIN (-6125 4050) BN 1
J 0
(-6137 4058);
DISPLAY 0.489362 (-6137 4058);
PAINT GREEN (-6137 4058);
FORCEPROP 2 LAST CDS_LIB mstr_standard
J 0
(-6075 4050);
DISPLAY 0.723404 (-6075 4050);
PAINT MONO (-6075 4050);
DISPLAY INVISIBLE (-6075 4050);
FORCEPROP 1 LAST BODY_TYPE PLUMBING
J 0
(-6075 4100);
DISPLAY 0.872340 (-6075 4100);
PAINT GREEN (-6075 4100);
DISPLAY INVISIBLE (-6075 4100);
FORCEPROP 1 LAST HDL_TAP TRUE
J 0
(-5750 3925);
DISPLAY 0.872340 (-5750 3925);
DISPLAY INVISIBLE (-5750 3925);
FORCEPROP 1 LAST PATH I237
J 0
(-6077 4050);
DISPLAY 0.872340 (-6077 4050);
PAINT GREEN (-6077 4050);
DISPLAY INVISIBLE (-6077 4050);
FORCEADD TAP..1
(-6075 4100);
FORCEPROP 3 LASTPIN (-6125 4100) SIG_NAME M_D_CPU0_SA_DQ<2>
J 0
(-6115 4110);
DISPLAY 0.659574 (-6115 4110);
PAINT MONO (-6115 4110);
DISPLAY INVISIBLE (-6115 4110);
FORCEPROP 1 LASTPIN (-6125 4100) BN 2
J 0
(-6137 4108);
DISPLAY 0.489362 (-6137 4108);
PAINT GREEN (-6137 4108);
FORCEPROP 2 LAST CDS_LIB mstr_standard
J 0
(-6075 4100);
DISPLAY 0.723404 (-6075 4100);
PAINT MONO (-6075 4100);
DISPLAY INVISIBLE (-6075 4100);
FORCEPROP 1 LAST BODY_TYPE PLUMBING
J 0
(-6075 4150);
DISPLAY 0.872340 (-6075 4150);
PAINT GREEN (-6075 4150);
DISPLAY INVISIBLE (-6075 4150);
FORCEPROP 1 LAST HDL_TAP TRUE
J 0
(-5750 3975);
DISPLAY 0.872340 (-5750 3975);
DISPLAY INVISIBLE (-5750 3975);
FORCEPROP 1 LAST PATH I238
J 0
(-6077 4100);
DISPLAY 0.872340 (-6077 4100);
PAINT GREEN (-6077 4100);
DISPLAY INVISIBLE (-6077 4100);
FORCEADD TAP..1
R 2
(-7775 4150);
FORCEPROP 3 LASTPIN (-7725 4150) SIG_NAME M_D_CPU0_SA_CB<7>
J 0
(-7715 4160);
DISPLAY 0.659574 (-7715 4160);
PAINT MONO (-7715 4160);
DISPLAY INVISIBLE (-7715 4160);
FORCEPROP 1 LASTPIN (-7725 4150) BN 7
J 2
(-7713 4158);
DISPLAY 0.489362 (-7713 4158);
PAINT GREEN (-7713 4158);
FORCEPROP 2 LAST CDS_LIB mstr_standard
J 0
(-7775 4150);
DISPLAY 0.723404 (-7775 4150);
PAINT MONO (-7775 4150);
DISPLAY INVISIBLE (-7775 4150);
FORCEPROP 1 LAST BODY_TYPE PLUMBING
J 2
(-7775 4200);
DISPLAY 0.872340 (-7775 4200);
PAINT GREEN (-7775 4200);
DISPLAY INVISIBLE (-7775 4200);
FORCEPROP 1 LAST HDL_TAP TRUE
J 2
(-8100 4025);
DISPLAY 0.872340 (-8100 4025);
DISPLAY INVISIBLE (-8100 4025);
FORCEPROP 1 LAST PATH I239
J 2
(-7773 4150);
DISPLAY 0.872340 (-7773 4150);
PAINT GREEN (-7773 4150);
DISPLAY INVISIBLE (-7773 4150);
FORCEADD TAP..1
R 2
(-7775 4850);
FORCEPROP 3 LASTPIN (-7725 4850) SIG_NAME M_D_CPU0_SB_CA<0>
J 0
(-7715 4860);
DISPLAY 0.659574 (-7715 4860);
PAINT MONO (-7715 4860);
DISPLAY INVISIBLE (-7715 4860);
FORCEPROP 1 LASTPIN (-7725 4850) BN 0
J 2
(-7713 4858);
DISPLAY 0.489362 (-7713 4858);
PAINT GREEN (-7713 4858);
FORCEPROP 2 LAST CDS_LIB mstr_standard
J 0
(-7775 4850);
DISPLAY 0.723404 (-7775 4850);
PAINT MONO (-7775 4850);
DISPLAY INVISIBLE (-7775 4850);
FORCEPROP 1 LAST BODY_TYPE PLUMBING
J 2
(-7775 4900);
DISPLAY 0.872340 (-7775 4900);
PAINT GREEN (-7775 4900);
DISPLAY INVISIBLE (-7775 4900);
FORCEPROP 1 LAST HDL_TAP TRUE
J 2
(-8100 4725);
DISPLAY 0.872340 (-8100 4725);
DISPLAY INVISIBLE (-8100 4725);
FORCEPROP 1 LAST PATH I240
J 2
(-7773 4850);
DISPLAY 0.872340 (-7773 4850);
PAINT GREEN (-7773 4850);
DISPLAY INVISIBLE (-7773 4850);
FORCEADD TAP..1
R 2
(-7775 4900);
FORCEPROP 3 LASTPIN (-7725 4900) SIG_NAME M_D_CPU0_SB_CA<1>
J 0
(-7715 4910);
DISPLAY 0.659574 (-7715 4910);
PAINT MONO (-7715 4910);
DISPLAY INVISIBLE (-7715 4910);
FORCEPROP 1 LASTPIN (-7725 4900) BN 1
J 2
(-7713 4908);
DISPLAY 0.489362 (-7713 4908);
PAINT GREEN (-7713 4908);
FORCEPROP 2 LAST CDS_LIB mstr_standard
J 0
(-7775 4900);
DISPLAY 0.723404 (-7775 4900);
PAINT MONO (-7775 4900);
DISPLAY INVISIBLE (-7775 4900);
FORCEPROP 1 LAST BODY_TYPE PLUMBING
J 2
(-7775 4950);
DISPLAY 0.872340 (-7775 4950);
PAINT GREEN (-7775 4950);
DISPLAY INVISIBLE (-7775 4950);
FORCEPROP 1 LAST HDL_TAP TRUE
J 2
(-8100 4775);
DISPLAY 0.872340 (-8100 4775);
DISPLAY INVISIBLE (-8100 4775);
FORCEPROP 1 LAST PATH I241
J 2
(-7773 4900);
DISPLAY 0.872340 (-7773 4900);
PAINT GREEN (-7773 4900);
DISPLAY INVISIBLE (-7773 4900);
FORCEADD TAP..1
R 2
(-7775 4950);
FORCEPROP 3 LASTPIN (-7725 4950) SIG_NAME M_D_CPU0_SB_CA<2>
J 0
(-7715 4960);
DISPLAY 0.659574 (-7715 4960);
PAINT MONO (-7715 4960);
DISPLAY INVISIBLE (-7715 4960);
FORCEPROP 1 LASTPIN (-7725 4950) BN 2
J 2
(-7713 4958);
DISPLAY 0.489362 (-7713 4958);
PAINT GREEN (-7713 4958);
FORCEPROP 2 LAST CDS_LIB mstr_standard
J 0
(-7775 4950);
DISPLAY 0.723404 (-7775 4950);
PAINT MONO (-7775 4950);
DISPLAY INVISIBLE (-7775 4950);
FORCEPROP 1 LAST BODY_TYPE PLUMBING
J 2
(-7775 5000);
DISPLAY 0.872340 (-7775 5000);
PAINT GREEN (-7775 5000);
DISPLAY INVISIBLE (-7775 5000);
FORCEPROP 1 LAST HDL_TAP TRUE
J 2
(-8100 4825);
DISPLAY 0.872340 (-8100 4825);
DISPLAY INVISIBLE (-8100 4825);
FORCEPROP 1 LAST PATH I242
J 2
(-7773 4950);
DISPLAY 0.872340 (-7773 4950);
PAINT GREEN (-7773 4950);
DISPLAY INVISIBLE (-7773 4950);
FORCEADD TAP..1
R 2
(-7775 5000);
FORCEPROP 3 LASTPIN (-7725 5000) SIG_NAME M_D_CPU0_SB_CA<3>
J 0
(-7715 5010);
DISPLAY 0.659574 (-7715 5010);
PAINT MONO (-7715 5010);
DISPLAY INVISIBLE (-7715 5010);
FORCEPROP 1 LASTPIN (-7725 5000) BN 3
J 2
(-7713 5008);
DISPLAY 0.489362 (-7713 5008);
PAINT GREEN (-7713 5008);
FORCEPROP 2 LAST CDS_LIB mstr_standard
J 0
(-7775 5000);
DISPLAY 0.723404 (-7775 5000);
PAINT MONO (-7775 5000);
DISPLAY INVISIBLE (-7775 5000);
FORCEPROP 1 LAST BODY_TYPE PLUMBING
J 2
(-7775 5050);
DISPLAY 0.872340 (-7775 5050);
PAINT GREEN (-7775 5050);
DISPLAY INVISIBLE (-7775 5050);
FORCEPROP 1 LAST HDL_TAP TRUE
J 2
(-8100 4875);
DISPLAY 0.872340 (-8100 4875);
DISPLAY INVISIBLE (-8100 4875);
FORCEPROP 1 LAST PATH I243
J 2
(-7773 5000);
DISPLAY 0.872340 (-7773 5000);
PAINT GREEN (-7773 5000);
DISPLAY INVISIBLE (-7773 5000);
FORCEADD TAP..1
R 2
(-7775 5050);
FORCEPROP 3 LASTPIN (-7725 5050) SIG_NAME M_D_CPU0_SB_CA<4>
J 0
(-7715 5060);
DISPLAY 0.659574 (-7715 5060);
PAINT MONO (-7715 5060);
DISPLAY INVISIBLE (-7715 5060);
FORCEPROP 1 LASTPIN (-7725 5050) BN 4
J 2
(-7713 5058);
DISPLAY 0.489362 (-7713 5058);
PAINT GREEN (-7713 5058);
FORCEPROP 2 LAST CDS_LIB mstr_standard
J 0
(-7775 5050);
DISPLAY 0.723404 (-7775 5050);
PAINT MONO (-7775 5050);
DISPLAY INVISIBLE (-7775 5050);
FORCEPROP 1 LAST BODY_TYPE PLUMBING
J 2
(-7775 5100);
DISPLAY 0.872340 (-7775 5100);
PAINT GREEN (-7775 5100);
DISPLAY INVISIBLE (-7775 5100);
FORCEPROP 1 LAST HDL_TAP TRUE
J 2
(-8100 4925);
DISPLAY 0.872340 (-8100 4925);
DISPLAY INVISIBLE (-8100 4925);
FORCEPROP 1 LAST PATH I244
J 2
(-7773 5050);
DISPLAY 0.872340 (-7773 5050);
PAINT GREEN (-7773 5050);
DISPLAY INVISIBLE (-7773 5050);
FORCEADD TAP..1
R 2
(-7775 5100);
FORCEPROP 3 LASTPIN (-7725 5100) SIG_NAME M_D_CPU0_SB_CA<5>
J 0
(-7715 5110);
DISPLAY 0.659574 (-7715 5110);
PAINT MONO (-7715 5110);
DISPLAY INVISIBLE (-7715 5110);
FORCEPROP 1 LASTPIN (-7725 5100) BN 5
J 2
(-7713 5108);
DISPLAY 0.489362 (-7713 5108);
PAINT GREEN (-7713 5108);
FORCEPROP 2 LAST CDS_LIB mstr_standard
J 0
(-7775 5100);
DISPLAY 0.723404 (-7775 5100);
PAINT MONO (-7775 5100);
DISPLAY INVISIBLE (-7775 5100);
FORCEPROP 1 LAST BODY_TYPE PLUMBING
J 2
(-7775 5150);
DISPLAY 0.872340 (-7775 5150);
PAINT GREEN (-7775 5150);
DISPLAY INVISIBLE (-7775 5150);
FORCEPROP 1 LAST HDL_TAP TRUE
J 2
(-8100 4975);
DISPLAY 0.872340 (-8100 4975);
DISPLAY INVISIBLE (-8100 4975);
FORCEPROP 1 LAST PATH I245
J 2
(-7773 5100);
DISPLAY 0.872340 (-7773 5100);
PAINT GREEN (-7773 5100);
DISPLAY INVISIBLE (-7773 5100);
FORCEADD TAP..1
R 2
(-7775 5150);
FORCEPROP 3 LASTPIN (-7725 5150) SIG_NAME M_D_CPU0_SB_CA<6>
J 0
(-7715 5160);
DISPLAY 0.659574 (-7715 5160);
PAINT MONO (-7715 5160);
DISPLAY INVISIBLE (-7715 5160);
FORCEPROP 1 LASTPIN (-7725 5150) BN 6
J 2
(-7713 5158);
DISPLAY 0.489362 (-7713 5158);
PAINT GREEN (-7713 5158);
FORCEPROP 2 LAST CDS_LIB mstr_standard
J 0
(-7775 5150);
DISPLAY 0.723404 (-7775 5150);
PAINT MONO (-7775 5150);
DISPLAY INVISIBLE (-7775 5150);
FORCEPROP 1 LAST BODY_TYPE PLUMBING
J 2
(-7775 5200);
DISPLAY 0.872340 (-7775 5200);
PAINT GREEN (-7775 5200);
DISPLAY INVISIBLE (-7775 5200);
FORCEPROP 1 LAST HDL_TAP TRUE
J 2
(-8100 5025);
DISPLAY 0.872340 (-8100 5025);
DISPLAY INVISIBLE (-8100 5025);
FORCEPROP 1 LAST PATH I246
J 2
(-7773 5150);
DISPLAY 0.872340 (-7773 5150);
PAINT GREEN (-7773 5150);
DISPLAY INVISIBLE (-7773 5150);
FORCEADD TAP..1
R 2
(-7775 5250);
FORCEPROP 3 LASTPIN (-7725 5250) SIG_NAME M_D_CPU0_SA_CA<0>
J 0
(-7715 5260);
DISPLAY 0.659574 (-7715 5260);
PAINT MONO (-7715 5260);
DISPLAY INVISIBLE (-7715 5260);
FORCEPROP 1 LASTPIN (-7725 5250) BN 0
J 2
(-7713 5258);
DISPLAY 0.489362 (-7713 5258);
PAINT GREEN (-7713 5258);
FORCEPROP 2 LAST CDS_LIB mstr_standard
J 0
(-7775 5250);
DISPLAY 0.723404 (-7775 5250);
PAINT MONO (-7775 5250);
DISPLAY INVISIBLE (-7775 5250);
FORCEPROP 1 LAST BODY_TYPE PLUMBING
J 2
(-7775 5300);
DISPLAY 0.872340 (-7775 5300);
PAINT GREEN (-7775 5300);
DISPLAY INVISIBLE (-7775 5300);
FORCEPROP 1 LAST HDL_TAP TRUE
J 2
(-8100 5125);
DISPLAY 0.872340 (-8100 5125);
DISPLAY INVISIBLE (-8100 5125);
FORCEPROP 1 LAST PATH I247
J 2
(-7773 5250);
DISPLAY 0.872340 (-7773 5250);
PAINT GREEN (-7773 5250);
DISPLAY INVISIBLE (-7773 5250);
FORCEADD TAP..1
R 2
(-7775 5300);
FORCEPROP 3 LASTPIN (-7725 5300) SIG_NAME M_D_CPU0_SA_CA<1>
J 0
(-7715 5310);
DISPLAY 0.659574 (-7715 5310);
PAINT MONO (-7715 5310);
DISPLAY INVISIBLE (-7715 5310);
FORCEPROP 1 LASTPIN (-7725 5300) BN 1
J 2
(-7713 5308);
DISPLAY 0.489362 (-7713 5308);
PAINT GREEN (-7713 5308);
FORCEPROP 2 LAST CDS_LIB mstr_standard
J 0
(-7775 5300);
DISPLAY 0.723404 (-7775 5300);
PAINT MONO (-7775 5300);
DISPLAY INVISIBLE (-7775 5300);
FORCEPROP 1 LAST BODY_TYPE PLUMBING
J 2
(-7775 5350);
DISPLAY 0.872340 (-7775 5350);
PAINT GREEN (-7775 5350);
DISPLAY INVISIBLE (-7775 5350);
FORCEPROP 1 LAST HDL_TAP TRUE
J 2
(-8100 5175);
DISPLAY 0.872340 (-8100 5175);
DISPLAY INVISIBLE (-8100 5175);
FORCEPROP 1 LAST PATH I248
J 2
(-7773 5300);
DISPLAY 0.872340 (-7773 5300);
PAINT GREEN (-7773 5300);
DISPLAY INVISIBLE (-7773 5300);
FORCEADD TAP..1
R 2
(-7775 5350);
FORCEPROP 3 LASTPIN (-7725 5350) SIG_NAME M_D_CPU0_SA_CA<2>
J 0
(-7715 5360);
DISPLAY 0.659574 (-7715 5360);
PAINT MONO (-7715 5360);
DISPLAY INVISIBLE (-7715 5360);
FORCEPROP 1 LASTPIN (-7725 5350) BN 2
J 2
(-7713 5358);
DISPLAY 0.489362 (-7713 5358);
PAINT GREEN (-7713 5358);
FORCEPROP 2 LAST CDS_LIB mstr_standard
J 0
(-7775 5350);
DISPLAY 0.723404 (-7775 5350);
PAINT MONO (-7775 5350);
DISPLAY INVISIBLE (-7775 5350);
FORCEPROP 1 LAST BODY_TYPE PLUMBING
J 2
(-7775 5400);
DISPLAY 0.872340 (-7775 5400);
PAINT GREEN (-7775 5400);
DISPLAY INVISIBLE (-7775 5400);
FORCEPROP 1 LAST HDL_TAP TRUE
J 2
(-8100 5225);
DISPLAY 0.872340 (-8100 5225);
DISPLAY INVISIBLE (-8100 5225);
FORCEPROP 1 LAST PATH I249
J 2
(-7773 5350);
DISPLAY 0.872340 (-7773 5350);
PAINT GREEN (-7773 5350);
DISPLAY INVISIBLE (-7773 5350);
FORCEADD TAP..1
R 2
(-7775 5400);
FORCEPROP 3 LASTPIN (-7725 5400) SIG_NAME M_D_CPU0_SA_CA<3>
J 0
(-7715 5410);
DISPLAY 0.659574 (-7715 5410);
PAINT MONO (-7715 5410);
DISPLAY INVISIBLE (-7715 5410);
FORCEPROP 1 LASTPIN (-7725 5400) BN 3
J 2
(-7713 5408);
DISPLAY 0.489362 (-7713 5408);
PAINT GREEN (-7713 5408);
FORCEPROP 2 LAST CDS_LIB mstr_standard
J 0
(-7775 5400);
DISPLAY 0.723404 (-7775 5400);
PAINT MONO (-7775 5400);
DISPLAY INVISIBLE (-7775 5400);
FORCEPROP 1 LAST BODY_TYPE PLUMBING
J 2
(-7775 5450);
DISPLAY 0.872340 (-7775 5450);
PAINT GREEN (-7775 5450);
DISPLAY INVISIBLE (-7775 5450);
FORCEPROP 1 LAST HDL_TAP TRUE
J 2
(-8100 5275);
DISPLAY 0.872340 (-8100 5275);
DISPLAY INVISIBLE (-8100 5275);
FORCEPROP 1 LAST PATH I250
J 2
(-7773 5400);
DISPLAY 0.872340 (-7773 5400);
PAINT GREEN (-7773 5400);
DISPLAY INVISIBLE (-7773 5400);
FORCEADD TAP..1
R 2
(-7775 5450);
FORCEPROP 3 LASTPIN (-7725 5450) SIG_NAME M_D_CPU0_SA_CA<4>
J 0
(-7715 5460);
DISPLAY 0.659574 (-7715 5460);
PAINT MONO (-7715 5460);
DISPLAY INVISIBLE (-7715 5460);
FORCEPROP 1 LASTPIN (-7725 5450) BN 4
J 2
(-7713 5458);
DISPLAY 0.489362 (-7713 5458);
PAINT GREEN (-7713 5458);
FORCEPROP 2 LAST CDS_LIB mstr_standard
J 0
(-7775 5450);
DISPLAY 0.723404 (-7775 5450);
PAINT MONO (-7775 5450);
DISPLAY INVISIBLE (-7775 5450);
FORCEPROP 1 LAST BODY_TYPE PLUMBING
J 2
(-7775 5500);
DISPLAY 0.872340 (-7775 5500);
PAINT GREEN (-7775 5500);
DISPLAY INVISIBLE (-7775 5500);
FORCEPROP 1 LAST HDL_TAP TRUE
J 2
(-8100 5325);
DISPLAY 0.872340 (-8100 5325);
DISPLAY INVISIBLE (-8100 5325);
FORCEPROP 1 LAST PATH I251
J 2
(-7773 5450);
DISPLAY 0.872340 (-7773 5450);
PAINT GREEN (-7773 5450);
DISPLAY INVISIBLE (-7773 5450);
FORCEADD TAP..1
R 2
(-7775 5500);
FORCEPROP 3 LASTPIN (-7725 5500) SIG_NAME M_D_CPU0_SA_CA<5>
J 0
(-7715 5510);
DISPLAY 0.659574 (-7715 5510);
PAINT MONO (-7715 5510);
DISPLAY INVISIBLE (-7715 5510);
FORCEPROP 1 LASTPIN (-7725 5500) BN 5
J 2
(-7713 5508);
DISPLAY 0.489362 (-7713 5508);
PAINT GREEN (-7713 5508);
FORCEPROP 2 LAST CDS_LIB mstr_standard
J 0
(-7775 5500);
DISPLAY 0.723404 (-7775 5500);
PAINT MONO (-7775 5500);
DISPLAY INVISIBLE (-7775 5500);
FORCEPROP 1 LAST BODY_TYPE PLUMBING
J 2
(-7775 5550);
DISPLAY 0.872340 (-7775 5550);
PAINT GREEN (-7775 5550);
DISPLAY INVISIBLE (-7775 5550);
FORCEPROP 1 LAST HDL_TAP TRUE
J 2
(-8100 5375);
DISPLAY 0.872340 (-8100 5375);
DISPLAY INVISIBLE (-8100 5375);
FORCEPROP 1 LAST PATH I252
J 2
(-7773 5500);
DISPLAY 0.872340 (-7773 5500);
PAINT GREEN (-7773 5500);
DISPLAY INVISIBLE (-7773 5500);
FORCEADD TAP..1
R 2
(-7775 5550);
FORCEPROP 3 LASTPIN (-7725 5550) SIG_NAME M_D_CPU0_SA_CA<6>
J 0
(-7715 5560);
DISPLAY 0.659574 (-7715 5560);
PAINT MONO (-7715 5560);
DISPLAY INVISIBLE (-7715 5560);
FORCEPROP 1 LASTPIN (-7725 5550) BN 6
J 2
(-7713 5558);
DISPLAY 0.489362 (-7713 5558);
PAINT GREEN (-7713 5558);
FORCEPROP 2 LAST CDS_LIB mstr_standard
J 0
(-7775 5550);
DISPLAY 0.723404 (-7775 5550);
PAINT MONO (-7775 5550);
DISPLAY INVISIBLE (-7775 5550);
FORCEPROP 1 LAST BODY_TYPE PLUMBING
J 2
(-7775 5600);
DISPLAY 0.872340 (-7775 5600);
PAINT GREEN (-7775 5600);
DISPLAY INVISIBLE (-7775 5600);
FORCEPROP 1 LAST HDL_TAP TRUE
J 2
(-8100 5425);
DISPLAY 0.872340 (-8100 5425);
DISPLAY INVISIBLE (-8100 5425);
FORCEPROP 1 LAST PATH I253
J 2
(-7773 5550);
DISPLAY 0.872340 (-7773 5550);
PAINT GREEN (-7773 5550);
DISPLAY INVISIBLE (-7773 5550);
FORCEADD TAP..1
(-6075 4150);
FORCEPROP 3 LASTPIN (-6125 4150) SIG_NAME M_D_CPU0_SA_DQ<3>
J 0
(-6115 4160);
DISPLAY 0.659574 (-6115 4160);
PAINT MONO (-6115 4160);
DISPLAY INVISIBLE (-6115 4160);
FORCEPROP 1 LASTPIN (-6125 4150) BN 3
J 0
(-6137 4158);
DISPLAY 0.489362 (-6137 4158);
PAINT GREEN (-6137 4158);
FORCEPROP 2 LAST CDS_LIB mstr_standard
J 0
(-6075 4150);
DISPLAY 0.723404 (-6075 4150);
PAINT MONO (-6075 4150);
DISPLAY INVISIBLE (-6075 4150);
FORCEPROP 1 LAST BODY_TYPE PLUMBING
J 0
(-6075 4200);
DISPLAY 0.872340 (-6075 4200);
PAINT GREEN (-6075 4200);
DISPLAY INVISIBLE (-6075 4200);
FORCEPROP 1 LAST HDL_TAP TRUE
J 0
(-5750 4025);
DISPLAY 0.872340 (-5750 4025);
DISPLAY INVISIBLE (-5750 4025);
FORCEPROP 1 LAST PATH I254
J 0
(-6077 4150);
DISPLAY 0.872340 (-6077 4150);
PAINT GREEN (-6077 4150);
DISPLAY INVISIBLE (-6077 4150);
FORCEADD TAP..1
(-6075 4200);
FORCEPROP 3 LASTPIN (-6125 4200) SIG_NAME M_D_CPU0_SA_DQ<4>
J 0
(-6115 4210);
DISPLAY 0.659574 (-6115 4210);
PAINT MONO (-6115 4210);
DISPLAY INVISIBLE (-6115 4210);
FORCEPROP 1 LASTPIN (-6125 4200) BN 4
J 0
(-6137 4208);
DISPLAY 0.489362 (-6137 4208);
PAINT GREEN (-6137 4208);
FORCEPROP 2 LAST CDS_LIB mstr_standard
J 0
(-6075 4200);
DISPLAY 0.723404 (-6075 4200);
PAINT MONO (-6075 4200);
DISPLAY INVISIBLE (-6075 4200);
FORCEPROP 1 LAST BODY_TYPE PLUMBING
J 0
(-6075 4250);
DISPLAY 0.872340 (-6075 4250);
PAINT GREEN (-6075 4250);
DISPLAY INVISIBLE (-6075 4250);
FORCEPROP 1 LAST HDL_TAP TRUE
J 0
(-5750 4075);
DISPLAY 0.872340 (-5750 4075);
DISPLAY INVISIBLE (-5750 4075);
FORCEPROP 1 LAST PATH I255
J 0
(-6077 4200);
DISPLAY 0.872340 (-6077 4200);
PAINT GREEN (-6077 4200);
DISPLAY INVISIBLE (-6077 4200);
FORCEADD TAP..1
(-6075 4250);
FORCEPROP 3 LASTPIN (-6125 4250) SIG_NAME M_D_CPU0_SA_DQ<5>
J 0
(-6115 4260);
DISPLAY 0.659574 (-6115 4260);
PAINT MONO (-6115 4260);
DISPLAY INVISIBLE (-6115 4260);
FORCEPROP 1 LASTPIN (-6125 4250) BN 5
J 0
(-6137 4258);
DISPLAY 0.489362 (-6137 4258);
PAINT GREEN (-6137 4258);
FORCEPROP 2 LAST CDS_LIB mstr_standard
J 0
(-6075 4250);
DISPLAY 0.723404 (-6075 4250);
PAINT MONO (-6075 4250);
DISPLAY INVISIBLE (-6075 4250);
FORCEPROP 1 LAST BODY_TYPE PLUMBING
J 0
(-6075 4300);
DISPLAY 0.872340 (-6075 4300);
PAINT GREEN (-6075 4300);
DISPLAY INVISIBLE (-6075 4300);
FORCEPROP 1 LAST HDL_TAP TRUE
J 0
(-5750 4125);
DISPLAY 0.872340 (-5750 4125);
DISPLAY INVISIBLE (-5750 4125);
FORCEPROP 1 LAST PATH I256
J 0
(-6077 4250);
DISPLAY 0.872340 (-6077 4250);
PAINT GREEN (-6077 4250);
DISPLAY INVISIBLE (-6077 4250);
FORCEADD TAP..1
(-6075 4350);
FORCEPROP 3 LASTPIN (-6125 4350) SIG_NAME M_D_CPU0_SA_DQ<7>
J 0
(-6115 4360);
DISPLAY 0.659574 (-6115 4360);
PAINT MONO (-6115 4360);
DISPLAY INVISIBLE (-6115 4360);
FORCEPROP 1 LASTPIN (-6125 4350) BN 7
J 0
(-6137 4358);
DISPLAY 0.489362 (-6137 4358);
PAINT GREEN (-6137 4358);
FORCEPROP 2 LAST CDS_LIB mstr_standard
J 0
(-6075 4350);
DISPLAY 0.723404 (-6075 4350);
PAINT MONO (-6075 4350);
DISPLAY INVISIBLE (-6075 4350);
FORCEPROP 1 LAST BODY_TYPE PLUMBING
J 0
(-6075 4400);
DISPLAY 0.872340 (-6075 4400);
PAINT GREEN (-6075 4400);
DISPLAY INVISIBLE (-6075 4400);
FORCEPROP 1 LAST HDL_TAP TRUE
J 0
(-5750 4225);
DISPLAY 0.872340 (-5750 4225);
DISPLAY INVISIBLE (-5750 4225);
FORCEPROP 1 LAST PATH I257
J 0
(-6077 4350);
DISPLAY 0.872340 (-6077 4350);
PAINT GREEN (-6077 4350);
DISPLAY INVISIBLE (-6077 4350);
FORCEADD TAP..1
(-6075 4300);
FORCEPROP 3 LASTPIN (-6125 4300) SIG_NAME M_D_CPU0_SA_DQ<6>
J 0
(-6115 4310);
DISPLAY 0.659574 (-6115 4310);
PAINT MONO (-6115 4310);
DISPLAY INVISIBLE (-6115 4310);
FORCEPROP 1 LASTPIN (-6125 4300) BN 6
J 0
(-6137 4308);
DISPLAY 0.489362 (-6137 4308);
PAINT GREEN (-6137 4308);
FORCEPROP 2 LAST CDS_LIB mstr_standard
J 0
(-6075 4300);
DISPLAY 0.723404 (-6075 4300);
PAINT MONO (-6075 4300);
DISPLAY INVISIBLE (-6075 4300);
FORCEPROP 1 LAST BODY_TYPE PLUMBING
J 0
(-6075 4350);
DISPLAY 0.872340 (-6075 4350);
PAINT GREEN (-6075 4350);
DISPLAY INVISIBLE (-6075 4350);
FORCEPROP 1 LAST HDL_TAP TRUE
J 0
(-5750 4175);
DISPLAY 0.872340 (-5750 4175);
DISPLAY INVISIBLE (-5750 4175);
FORCEPROP 1 LAST PATH I258
J 0
(-6077 4300);
DISPLAY 0.872340 (-6077 4300);
PAINT GREEN (-6077 4300);
DISPLAY INVISIBLE (-6077 4300);
FORCEADD TAP..1
(-6075 4400);
FORCEPROP 3 LASTPIN (-6125 4400) SIG_NAME M_D_CPU0_SA_DQ<8>
J 0
(-6115 4410);
DISPLAY 0.659574 (-6115 4410);
PAINT MONO (-6115 4410);
DISPLAY INVISIBLE (-6115 4410);
FORCEPROP 1 LASTPIN (-6125 4400) BN 8
J 0
(-6137 4408);
DISPLAY 0.489362 (-6137 4408);
PAINT GREEN (-6137 4408);
FORCEPROP 2 LAST CDS_LIB mstr_standard
J 0
(-6075 4400);
DISPLAY 0.723404 (-6075 4400);
PAINT MONO (-6075 4400);
DISPLAY INVISIBLE (-6075 4400);
FORCEPROP 1 LAST BODY_TYPE PLUMBING
J 0
(-6075 4450);
DISPLAY 0.872340 (-6075 4450);
PAINT GREEN (-6075 4450);
DISPLAY INVISIBLE (-6075 4450);
FORCEPROP 1 LAST HDL_TAP TRUE
J 0
(-5750 4275);
DISPLAY 0.872340 (-5750 4275);
DISPLAY INVISIBLE (-5750 4275);
FORCEPROP 1 LAST PATH I259
J 0
(-6077 4400);
DISPLAY 0.872340 (-6077 4400);
PAINT GREEN (-6077 4400);
DISPLAY INVISIBLE (-6077 4400);
FORCEADD TAP..1
(-6075 4450);
FORCEPROP 3 LASTPIN (-6125 4450) SIG_NAME M_D_CPU0_SA_DQ<9>
J 0
(-6115 4460);
DISPLAY 0.659574 (-6115 4460);
PAINT MONO (-6115 4460);
DISPLAY INVISIBLE (-6115 4460);
FORCEPROP 1 LASTPIN (-6125 4450) BN 9
J 0
(-6137 4458);
DISPLAY 0.489362 (-6137 4458);
PAINT GREEN (-6137 4458);
FORCEPROP 2 LAST CDS_LIB mstr_standard
J 0
(-6075 4450);
DISPLAY 0.723404 (-6075 4450);
PAINT MONO (-6075 4450);
DISPLAY INVISIBLE (-6075 4450);
FORCEPROP 1 LAST BODY_TYPE PLUMBING
J 0
(-6075 4500);
DISPLAY 0.872340 (-6075 4500);
PAINT GREEN (-6075 4500);
DISPLAY INVISIBLE (-6075 4500);
FORCEPROP 1 LAST HDL_TAP TRUE
J 0
(-5750 4325);
DISPLAY 0.872340 (-5750 4325);
DISPLAY INVISIBLE (-5750 4325);
FORCEPROP 1 LAST PATH I260
J 0
(-6077 4450);
DISPLAY 0.872340 (-6077 4450);
PAINT GREEN (-6077 4450);
DISPLAY INVISIBLE (-6077 4450);
FORCEADD TAP..1
(-6075 4500);
FORCEPROP 3 LASTPIN (-6125 4500) SIG_NAME M_D_CPU0_SA_DQ<10>
J 0
(-6115 4510);
DISPLAY 0.659574 (-6115 4510);
PAINT MONO (-6115 4510);
DISPLAY INVISIBLE (-6115 4510);
FORCEPROP 1 LASTPIN (-6125 4500) BN 10
J 0
(-6137 4508);
DISPLAY 0.489362 (-6137 4508);
PAINT GREEN (-6137 4508);
FORCEPROP 2 LAST CDS_LIB mstr_standard
J 0
(-6075 4500);
DISPLAY 0.723404 (-6075 4500);
PAINT MONO (-6075 4500);
DISPLAY INVISIBLE (-6075 4500);
FORCEPROP 1 LAST BODY_TYPE PLUMBING
J 0
(-6075 4550);
DISPLAY 0.872340 (-6075 4550);
PAINT GREEN (-6075 4550);
DISPLAY INVISIBLE (-6075 4550);
FORCEPROP 1 LAST HDL_TAP TRUE
J 0
(-5750 4375);
DISPLAY 0.872340 (-5750 4375);
DISPLAY INVISIBLE (-5750 4375);
FORCEPROP 1 LAST PATH I261
J 0
(-6077 4500);
DISPLAY 0.872340 (-6077 4500);
PAINT GREEN (-6077 4500);
DISPLAY INVISIBLE (-6077 4500);
FORCEADD TAP..1
(-6075 4550);
FORCEPROP 3 LASTPIN (-6125 4550) SIG_NAME M_D_CPU0_SA_DQ<11>
J 0
(-6115 4560);
DISPLAY 0.659574 (-6115 4560);
PAINT MONO (-6115 4560);
DISPLAY INVISIBLE (-6115 4560);
FORCEPROP 1 LASTPIN (-6125 4550) BN 11
J 0
(-6137 4558);
DISPLAY 0.489362 (-6137 4558);
PAINT GREEN (-6137 4558);
FORCEPROP 2 LAST CDS_LIB mstr_standard
J 0
(-6075 4550);
DISPLAY 0.723404 (-6075 4550);
PAINT MONO (-6075 4550);
DISPLAY INVISIBLE (-6075 4550);
FORCEPROP 1 LAST BODY_TYPE PLUMBING
J 0
(-6075 4600);
DISPLAY 0.872340 (-6075 4600);
PAINT GREEN (-6075 4600);
DISPLAY INVISIBLE (-6075 4600);
FORCEPROP 1 LAST HDL_TAP TRUE
J 0
(-5750 4425);
DISPLAY 0.872340 (-5750 4425);
DISPLAY INVISIBLE (-5750 4425);
FORCEPROP 1 LAST PATH I262
J 0
(-6077 4550);
DISPLAY 0.872340 (-6077 4550);
PAINT GREEN (-6077 4550);
DISPLAY INVISIBLE (-6077 4550);
FORCEADD TAP..1
(-6075 4600);
FORCEPROP 3 LASTPIN (-6125 4600) SIG_NAME M_D_CPU0_SA_DQ<12>
J 0
(-6115 4610);
DISPLAY 0.659574 (-6115 4610);
PAINT MONO (-6115 4610);
DISPLAY INVISIBLE (-6115 4610);
FORCEPROP 1 LASTPIN (-6125 4600) BN 12
J 0
(-6137 4608);
DISPLAY 0.489362 (-6137 4608);
PAINT GREEN (-6137 4608);
FORCEPROP 2 LAST CDS_LIB mstr_standard
J 0
(-6075 4600);
DISPLAY 0.723404 (-6075 4600);
PAINT MONO (-6075 4600);
DISPLAY INVISIBLE (-6075 4600);
FORCEPROP 1 LAST BODY_TYPE PLUMBING
J 0
(-6075 4650);
DISPLAY 0.872340 (-6075 4650);
PAINT GREEN (-6075 4650);
DISPLAY INVISIBLE (-6075 4650);
FORCEPROP 1 LAST HDL_TAP TRUE
J 0
(-5750 4475);
DISPLAY 0.872340 (-5750 4475);
DISPLAY INVISIBLE (-5750 4475);
FORCEPROP 1 LAST PATH I263
J 0
(-6077 4600);
DISPLAY 0.872340 (-6077 4600);
PAINT GREEN (-6077 4600);
DISPLAY INVISIBLE (-6077 4600);
FORCEADD TAP..1
(-6075 4650);
FORCEPROP 3 LASTPIN (-6125 4650) SIG_NAME M_D_CPU0_SA_DQ<13>
J 0
(-6115 4660);
DISPLAY 0.659574 (-6115 4660);
PAINT MONO (-6115 4660);
DISPLAY INVISIBLE (-6115 4660);
FORCEPROP 1 LASTPIN (-6125 4650) BN 13
J 0
(-6137 4658);
DISPLAY 0.489362 (-6137 4658);
PAINT GREEN (-6137 4658);
FORCEPROP 2 LAST CDS_LIB mstr_standard
J 0
(-6075 4650);
DISPLAY 0.723404 (-6075 4650);
PAINT MONO (-6075 4650);
DISPLAY INVISIBLE (-6075 4650);
FORCEPROP 1 LAST BODY_TYPE PLUMBING
J 0
(-6075 4700);
DISPLAY 0.872340 (-6075 4700);
PAINT GREEN (-6075 4700);
DISPLAY INVISIBLE (-6075 4700);
FORCEPROP 1 LAST HDL_TAP TRUE
J 0
(-5750 4525);
DISPLAY 0.872340 (-5750 4525);
DISPLAY INVISIBLE (-5750 4525);
FORCEPROP 1 LAST PATH I264
J 0
(-6077 4650);
DISPLAY 0.872340 (-6077 4650);
PAINT GREEN (-6077 4650);
DISPLAY INVISIBLE (-6077 4650);
FORCEADD TAP..1
(-6075 4700);
FORCEPROP 3 LASTPIN (-6125 4700) SIG_NAME M_D_CPU0_SA_DQ<14>
J 0
(-6115 4710);
DISPLAY 0.659574 (-6115 4710);
PAINT MONO (-6115 4710);
DISPLAY INVISIBLE (-6115 4710);
FORCEPROP 1 LASTPIN (-6125 4700) BN 14
J 0
(-6137 4708);
DISPLAY 0.489362 (-6137 4708);
PAINT GREEN (-6137 4708);
FORCEPROP 2 LAST CDS_LIB mstr_standard
J 0
(-6075 4700);
DISPLAY 0.723404 (-6075 4700);
PAINT MONO (-6075 4700);
DISPLAY INVISIBLE (-6075 4700);
FORCEPROP 1 LAST BODY_TYPE PLUMBING
J 0
(-6075 4750);
DISPLAY 0.872340 (-6075 4750);
PAINT GREEN (-6075 4750);
DISPLAY INVISIBLE (-6075 4750);
FORCEPROP 1 LAST HDL_TAP TRUE
J 0
(-5750 4575);
DISPLAY 0.872340 (-5750 4575);
DISPLAY INVISIBLE (-5750 4575);
FORCEPROP 1 LAST PATH I265
J 0
(-6077 4700);
DISPLAY 0.872340 (-6077 4700);
PAINT GREEN (-6077 4700);
DISPLAY INVISIBLE (-6077 4700);
FORCEADD TAP..1
(-6075 4750);
FORCEPROP 3 LASTPIN (-6125 4750) SIG_NAME M_D_CPU0_SA_DQ<15>
J 0
(-6115 4760);
DISPLAY 0.659574 (-6115 4760);
PAINT MONO (-6115 4760);
DISPLAY INVISIBLE (-6115 4760);
FORCEPROP 1 LASTPIN (-6125 4750) BN 15
J 0
(-6137 4758);
DISPLAY 0.489362 (-6137 4758);
PAINT GREEN (-6137 4758);
FORCEPROP 2 LAST CDS_LIB mstr_standard
J 0
(-6075 4750);
DISPLAY 0.723404 (-6075 4750);
PAINT MONO (-6075 4750);
DISPLAY INVISIBLE (-6075 4750);
FORCEPROP 1 LAST BODY_TYPE PLUMBING
J 0
(-6075 4800);
DISPLAY 0.872340 (-6075 4800);
PAINT GREEN (-6075 4800);
DISPLAY INVISIBLE (-6075 4800);
FORCEPROP 1 LAST HDL_TAP TRUE
J 0
(-5750 4625);
DISPLAY 0.872340 (-5750 4625);
DISPLAY INVISIBLE (-5750 4625);
FORCEPROP 1 LAST PATH I266
J 0
(-6077 4750);
DISPLAY 0.872340 (-6077 4750);
PAINT GREEN (-6077 4750);
DISPLAY INVISIBLE (-6077 4750);
FORCEADD TAP..1
(-6075 4850);
FORCEPROP 3 LASTPIN (-6125 4850) SIG_NAME M_D_CPU0_SA_DQ<17>
J 0
(-6115 4860);
DISPLAY 0.659574 (-6115 4860);
PAINT MONO (-6115 4860);
DISPLAY INVISIBLE (-6115 4860);
FORCEPROP 1 LASTPIN (-6125 4850) BN 17
J 0
(-6137 4858);
DISPLAY 0.489362 (-6137 4858);
PAINT GREEN (-6137 4858);
FORCEPROP 2 LAST CDS_LIB mstr_standard
J 0
(-6075 4850);
DISPLAY 0.723404 (-6075 4850);
PAINT MONO (-6075 4850);
DISPLAY INVISIBLE (-6075 4850);
FORCEPROP 1 LAST BODY_TYPE PLUMBING
J 0
(-6075 4900);
DISPLAY 0.872340 (-6075 4900);
PAINT GREEN (-6075 4900);
DISPLAY INVISIBLE (-6075 4900);
FORCEPROP 1 LAST HDL_TAP TRUE
J 0
(-5750 4725);
DISPLAY 0.872340 (-5750 4725);
DISPLAY INVISIBLE (-5750 4725);
FORCEPROP 1 LAST PATH I267
J 0
(-6077 4850);
DISPLAY 0.872340 (-6077 4850);
PAINT GREEN (-6077 4850);
DISPLAY INVISIBLE (-6077 4850);
FORCEADD TAP..1
(-6075 4900);
FORCEPROP 3 LASTPIN (-6125 4900) SIG_NAME M_D_CPU0_SA_DQ<18>
J 0
(-6115 4910);
DISPLAY 0.659574 (-6115 4910);
PAINT MONO (-6115 4910);
DISPLAY INVISIBLE (-6115 4910);
FORCEPROP 1 LASTPIN (-6125 4900) BN 18
J 0
(-6137 4908);
DISPLAY 0.489362 (-6137 4908);
PAINT GREEN (-6137 4908);
FORCEPROP 2 LAST CDS_LIB mstr_standard
J 0
(-6075 4900);
DISPLAY 0.723404 (-6075 4900);
PAINT MONO (-6075 4900);
DISPLAY INVISIBLE (-6075 4900);
FORCEPROP 1 LAST BODY_TYPE PLUMBING
J 0
(-6075 4950);
DISPLAY 0.872340 (-6075 4950);
PAINT GREEN (-6075 4950);
DISPLAY INVISIBLE (-6075 4950);
FORCEPROP 1 LAST HDL_TAP TRUE
J 0
(-5750 4775);
DISPLAY 0.872340 (-5750 4775);
DISPLAY INVISIBLE (-5750 4775);
FORCEPROP 1 LAST PATH I268
J 0
(-6077 4900);
DISPLAY 0.872340 (-6077 4900);
PAINT GREEN (-6077 4900);
DISPLAY INVISIBLE (-6077 4900);
FORCEADD TAP..1
(-6075 4800);
FORCEPROP 3 LASTPIN (-6125 4800) SIG_NAME M_D_CPU0_SA_DQ<16>
J 0
(-6115 4810);
DISPLAY 0.659574 (-6115 4810);
PAINT MONO (-6115 4810);
DISPLAY INVISIBLE (-6115 4810);
FORCEPROP 1 LASTPIN (-6125 4800) BN 16
J 0
(-6137 4808);
DISPLAY 0.489362 (-6137 4808);
PAINT GREEN (-6137 4808);
FORCEPROP 2 LAST CDS_LIB mstr_standard
J 0
(-6075 4800);
DISPLAY 0.723404 (-6075 4800);
PAINT MONO (-6075 4800);
DISPLAY INVISIBLE (-6075 4800);
FORCEPROP 1 LAST BODY_TYPE PLUMBING
J 0
(-6075 4850);
DISPLAY 0.872340 (-6075 4850);
PAINT GREEN (-6075 4850);
DISPLAY INVISIBLE (-6075 4850);
FORCEPROP 1 LAST HDL_TAP TRUE
J 0
(-5750 4675);
DISPLAY 0.872340 (-5750 4675);
DISPLAY INVISIBLE (-5750 4675);
FORCEPROP 1 LAST PATH I269
J 0
(-6077 4800);
DISPLAY 0.872340 (-6077 4800);
PAINT GREEN (-6077 4800);
DISPLAY INVISIBLE (-6077 4800);
FORCEADD TAP..1
(-6075 4950);
FORCEPROP 3 LASTPIN (-6125 4950) SIG_NAME M_D_CPU0_SA_DQ<19>
J 0
(-6115 4960);
DISPLAY 0.659574 (-6115 4960);
PAINT MONO (-6115 4960);
DISPLAY INVISIBLE (-6115 4960);
FORCEPROP 1 LASTPIN (-6125 4950) BN 19
J 0
(-6137 4958);
DISPLAY 0.489362 (-6137 4958);
PAINT GREEN (-6137 4958);
FORCEPROP 2 LAST CDS_LIB mstr_standard
J 0
(-6075 4950);
DISPLAY 0.723404 (-6075 4950);
PAINT MONO (-6075 4950);
DISPLAY INVISIBLE (-6075 4950);
FORCEPROP 1 LAST BODY_TYPE PLUMBING
J 0
(-6075 5000);
DISPLAY 0.872340 (-6075 5000);
PAINT GREEN (-6075 5000);
DISPLAY INVISIBLE (-6075 5000);
FORCEPROP 1 LAST HDL_TAP TRUE
J 0
(-5750 4825);
DISPLAY 0.872340 (-5750 4825);
DISPLAY INVISIBLE (-5750 4825);
FORCEPROP 1 LAST PATH I270
J 0
(-6077 4950);
DISPLAY 0.872340 (-6077 4950);
PAINT GREEN (-6077 4950);
DISPLAY INVISIBLE (-6077 4950);
FORCEADD TAP..1
(-6075 5000);
FORCEPROP 3 LASTPIN (-6125 5000) SIG_NAME M_D_CPU0_SA_DQ<20>
J 0
(-6115 5010);
DISPLAY 0.659574 (-6115 5010);
PAINT MONO (-6115 5010);
DISPLAY INVISIBLE (-6115 5010);
FORCEPROP 1 LASTPIN (-6125 5000) BN 20
J 0
(-6137 5008);
DISPLAY 0.489362 (-6137 5008);
PAINT GREEN (-6137 5008);
FORCEPROP 2 LAST CDS_LIB mstr_standard
J 0
(-6075 5000);
DISPLAY 0.723404 (-6075 5000);
PAINT MONO (-6075 5000);
DISPLAY INVISIBLE (-6075 5000);
FORCEPROP 1 LAST BODY_TYPE PLUMBING
J 0
(-6075 5050);
DISPLAY 0.872340 (-6075 5050);
PAINT GREEN (-6075 5050);
DISPLAY INVISIBLE (-6075 5050);
FORCEPROP 1 LAST HDL_TAP TRUE
J 0
(-5750 4875);
DISPLAY 0.872340 (-5750 4875);
DISPLAY INVISIBLE (-5750 4875);
FORCEPROP 1 LAST PATH I271
J 0
(-6077 5000);
DISPLAY 0.872340 (-6077 5000);
PAINT GREEN (-6077 5000);
DISPLAY INVISIBLE (-6077 5000);
FORCEADD TAP..1
(-6075 5100);
FORCEPROP 3 LASTPIN (-6125 5100) SIG_NAME M_D_CPU0_SA_DQ<22>
J 0
(-6115 5110);
DISPLAY 0.659574 (-6115 5110);
PAINT MONO (-6115 5110);
DISPLAY INVISIBLE (-6115 5110);
FORCEPROP 1 LASTPIN (-6125 5100) BN 22
J 0
(-6137 5108);
DISPLAY 0.489362 (-6137 5108);
PAINT GREEN (-6137 5108);
FORCEPROP 2 LAST CDS_LIB mstr_standard
J 0
(-6075 5100);
DISPLAY 0.723404 (-6075 5100);
PAINT MONO (-6075 5100);
DISPLAY INVISIBLE (-6075 5100);
FORCEPROP 1 LAST BODY_TYPE PLUMBING
J 0
(-6075 5150);
DISPLAY 0.872340 (-6075 5150);
PAINT GREEN (-6075 5150);
DISPLAY INVISIBLE (-6075 5150);
FORCEPROP 1 LAST HDL_TAP TRUE
J 0
(-5750 4975);
DISPLAY 0.872340 (-5750 4975);
DISPLAY INVISIBLE (-5750 4975);
FORCEPROP 1 LAST PATH I272
J 0
(-6077 5100);
DISPLAY 0.872340 (-6077 5100);
PAINT GREEN (-6077 5100);
DISPLAY INVISIBLE (-6077 5100);
FORCEADD TAP..1
(-6075 5050);
FORCEPROP 3 LASTPIN (-6125 5050) SIG_NAME M_D_CPU0_SA_DQ<21>
J 0
(-6115 5060);
DISPLAY 0.659574 (-6115 5060);
PAINT MONO (-6115 5060);
DISPLAY INVISIBLE (-6115 5060);
FORCEPROP 1 LASTPIN (-6125 5050) BN 21
J 0
(-6137 5058);
DISPLAY 0.489362 (-6137 5058);
PAINT GREEN (-6137 5058);
FORCEPROP 2 LAST CDS_LIB mstr_standard
J 0
(-6075 5050);
DISPLAY 0.723404 (-6075 5050);
PAINT MONO (-6075 5050);
DISPLAY INVISIBLE (-6075 5050);
FORCEPROP 1 LAST BODY_TYPE PLUMBING
J 0
(-6075 5100);
DISPLAY 0.872340 (-6075 5100);
PAINT GREEN (-6075 5100);
DISPLAY INVISIBLE (-6075 5100);
FORCEPROP 1 LAST HDL_TAP TRUE
J 0
(-5750 4925);
DISPLAY 0.872340 (-5750 4925);
DISPLAY INVISIBLE (-5750 4925);
FORCEPROP 1 LAST PATH I273
J 0
(-6077 5050);
DISPLAY 0.872340 (-6077 5050);
PAINT GREEN (-6077 5050);
DISPLAY INVISIBLE (-6077 5050);
FORCEADD TAP..1
(-6075 5150);
FORCEPROP 3 LASTPIN (-6125 5150) SIG_NAME M_D_CPU0_SA_DQ<23>
J 0
(-6115 5160);
DISPLAY 0.659574 (-6115 5160);
PAINT MONO (-6115 5160);
DISPLAY INVISIBLE (-6115 5160);
FORCEPROP 1 LASTPIN (-6125 5150) BN 23
J 0
(-6137 5158);
DISPLAY 0.489362 (-6137 5158);
PAINT GREEN (-6137 5158);
FORCEPROP 2 LAST CDS_LIB mstr_standard
J 0
(-6075 5150);
DISPLAY 0.723404 (-6075 5150);
PAINT MONO (-6075 5150);
DISPLAY INVISIBLE (-6075 5150);
FORCEPROP 1 LAST BODY_TYPE PLUMBING
J 0
(-6075 5200);
DISPLAY 0.872340 (-6075 5200);
PAINT GREEN (-6075 5200);
DISPLAY INVISIBLE (-6075 5200);
FORCEPROP 1 LAST HDL_TAP TRUE
J 0
(-5750 5025);
DISPLAY 0.872340 (-5750 5025);
DISPLAY INVISIBLE (-5750 5025);
FORCEPROP 1 LAST PATH I274
J 0
(-6077 5150);
DISPLAY 0.872340 (-6077 5150);
PAINT GREEN (-6077 5150);
DISPLAY INVISIBLE (-6077 5150);
FORCEADD TAP..1
(-6075 5200);
FORCEPROP 3 LASTPIN (-6125 5200) SIG_NAME M_D_CPU0_SA_DQ<24>
J 0
(-6115 5210);
DISPLAY 0.659574 (-6115 5210);
PAINT MONO (-6115 5210);
DISPLAY INVISIBLE (-6115 5210);
FORCEPROP 1 LASTPIN (-6125 5200) BN 24
J 0
(-6137 5208);
DISPLAY 0.489362 (-6137 5208);
PAINT GREEN (-6137 5208);
FORCEPROP 2 LAST CDS_LIB mstr_standard
J 0
(-6075 5200);
DISPLAY 0.723404 (-6075 5200);
PAINT MONO (-6075 5200);
DISPLAY INVISIBLE (-6075 5200);
FORCEPROP 1 LAST BODY_TYPE PLUMBING
J 0
(-6075 5250);
DISPLAY 0.872340 (-6075 5250);
PAINT GREEN (-6075 5250);
DISPLAY INVISIBLE (-6075 5250);
FORCEPROP 1 LAST HDL_TAP TRUE
J 0
(-5750 5075);
DISPLAY 0.872340 (-5750 5075);
DISPLAY INVISIBLE (-5750 5075);
FORCEPROP 1 LAST PATH I275
J 0
(-6077 5200);
DISPLAY 0.872340 (-6077 5200);
PAINT GREEN (-6077 5200);
DISPLAY INVISIBLE (-6077 5200);
FORCEADD TAP..1
(-6075 5250);
FORCEPROP 3 LASTPIN (-6125 5250) SIG_NAME M_D_CPU0_SA_DQ<25>
J 0
(-6115 5260);
DISPLAY 0.659574 (-6115 5260);
PAINT MONO (-6115 5260);
DISPLAY INVISIBLE (-6115 5260);
FORCEPROP 1 LASTPIN (-6125 5250) BN 25
J 0
(-6137 5258);
DISPLAY 0.489362 (-6137 5258);
PAINT GREEN (-6137 5258);
FORCEPROP 2 LAST CDS_LIB mstr_standard
J 0
(-6075 5250);
DISPLAY 0.723404 (-6075 5250);
PAINT MONO (-6075 5250);
DISPLAY INVISIBLE (-6075 5250);
FORCEPROP 1 LAST BODY_TYPE PLUMBING
J 0
(-6075 5300);
DISPLAY 0.872340 (-6075 5300);
PAINT GREEN (-6075 5300);
DISPLAY INVISIBLE (-6075 5300);
FORCEPROP 1 LAST HDL_TAP TRUE
J 0
(-5750 5125);
DISPLAY 0.872340 (-5750 5125);
DISPLAY INVISIBLE (-5750 5125);
FORCEPROP 1 LAST PATH I276
J 0
(-6077 5250);
DISPLAY 0.872340 (-6077 5250);
PAINT GREEN (-6077 5250);
DISPLAY INVISIBLE (-6077 5250);
FORCEADD TAP..1
(-6075 5300);
FORCEPROP 3 LASTPIN (-6125 5300) SIG_NAME M_D_CPU0_SA_DQ<26>
J 0
(-6115 5310);
DISPLAY 0.659574 (-6115 5310);
PAINT MONO (-6115 5310);
DISPLAY INVISIBLE (-6115 5310);
FORCEPROP 1 LASTPIN (-6125 5300) BN 26
J 0
(-6137 5308);
DISPLAY 0.489362 (-6137 5308);
PAINT GREEN (-6137 5308);
FORCEPROP 2 LAST CDS_LIB mstr_standard
J 0
(-6075 5300);
DISPLAY 0.723404 (-6075 5300);
PAINT MONO (-6075 5300);
DISPLAY INVISIBLE (-6075 5300);
FORCEPROP 1 LAST BODY_TYPE PLUMBING
J 0
(-6075 5350);
DISPLAY 0.872340 (-6075 5350);
PAINT GREEN (-6075 5350);
DISPLAY INVISIBLE (-6075 5350);
FORCEPROP 1 LAST HDL_TAP TRUE
J 0
(-5750 5175);
DISPLAY 0.872340 (-5750 5175);
DISPLAY INVISIBLE (-5750 5175);
FORCEPROP 1 LAST PATH I277
J 0
(-6077 5300);
DISPLAY 0.872340 (-6077 5300);
PAINT GREEN (-6077 5300);
DISPLAY INVISIBLE (-6077 5300);
FORCEADD TAP..1
(-6075 5350);
FORCEPROP 3 LASTPIN (-6125 5350) SIG_NAME M_D_CPU0_SA_DQ<27>
J 0
(-6115 5360);
DISPLAY 0.659574 (-6115 5360);
PAINT MONO (-6115 5360);
DISPLAY INVISIBLE (-6115 5360);
FORCEPROP 1 LASTPIN (-6125 5350) BN 27
J 0
(-6137 5358);
DISPLAY 0.489362 (-6137 5358);
PAINT GREEN (-6137 5358);
FORCEPROP 2 LAST CDS_LIB mstr_standard
J 0
(-6075 5350);
DISPLAY 0.723404 (-6075 5350);
PAINT MONO (-6075 5350);
DISPLAY INVISIBLE (-6075 5350);
FORCEPROP 1 LAST BODY_TYPE PLUMBING
J 0
(-6075 5400);
DISPLAY 0.872340 (-6075 5400);
PAINT GREEN (-6075 5400);
DISPLAY INVISIBLE (-6075 5400);
FORCEPROP 1 LAST HDL_TAP TRUE
J 0
(-5750 5225);
DISPLAY 0.872340 (-5750 5225);
DISPLAY INVISIBLE (-5750 5225);
FORCEPROP 1 LAST PATH I278
J 0
(-6077 5350);
DISPLAY 0.872340 (-6077 5350);
PAINT GREEN (-6077 5350);
DISPLAY INVISIBLE (-6077 5350);
FORCEADD TAP..1
(-6075 5400);
FORCEPROP 3 LASTPIN (-6125 5400) SIG_NAME M_D_CPU0_SA_DQ<28>
J 0
(-6115 5410);
DISPLAY 0.659574 (-6115 5410);
PAINT MONO (-6115 5410);
DISPLAY INVISIBLE (-6115 5410);
FORCEPROP 1 LASTPIN (-6125 5400) BN 28
J 0
(-6137 5408);
DISPLAY 0.489362 (-6137 5408);
PAINT GREEN (-6137 5408);
FORCEPROP 2 LAST CDS_LIB mstr_standard
J 0
(-6075 5400);
DISPLAY 0.723404 (-6075 5400);
PAINT MONO (-6075 5400);
DISPLAY INVISIBLE (-6075 5400);
FORCEPROP 1 LAST BODY_TYPE PLUMBING
J 0
(-6075 5450);
DISPLAY 0.872340 (-6075 5450);
PAINT GREEN (-6075 5450);
DISPLAY INVISIBLE (-6075 5450);
FORCEPROP 1 LAST HDL_TAP TRUE
J 0
(-5750 5275);
DISPLAY 0.872340 (-5750 5275);
DISPLAY INVISIBLE (-5750 5275);
FORCEPROP 1 LAST PATH I279
J 0
(-6077 5400);
DISPLAY 0.872340 (-6077 5400);
PAINT GREEN (-6077 5400);
DISPLAY INVISIBLE (-6077 5400);
FORCEADD TAP..1
(-6075 5450);
FORCEPROP 3 LASTPIN (-6125 5450) SIG_NAME M_D_CPU0_SA_DQ<29>
J 0
(-6115 5460);
DISPLAY 0.659574 (-6115 5460);
PAINT MONO (-6115 5460);
DISPLAY INVISIBLE (-6115 5460);
FORCEPROP 1 LASTPIN (-6125 5450) BN 29
J 0
(-6137 5458);
DISPLAY 0.489362 (-6137 5458);
PAINT GREEN (-6137 5458);
FORCEPROP 2 LAST CDS_LIB mstr_standard
J 0
(-6075 5450);
DISPLAY 0.723404 (-6075 5450);
PAINT MONO (-6075 5450);
DISPLAY INVISIBLE (-6075 5450);
FORCEPROP 1 LAST BODY_TYPE PLUMBING
J 0
(-6075 5500);
DISPLAY 0.872340 (-6075 5500);
PAINT GREEN (-6075 5500);
DISPLAY INVISIBLE (-6075 5500);
FORCEPROP 1 LAST HDL_TAP TRUE
J 0
(-5750 5325);
DISPLAY 0.872340 (-5750 5325);
DISPLAY INVISIBLE (-5750 5325);
FORCEPROP 1 LAST PATH I280
J 0
(-6077 5450);
DISPLAY 0.872340 (-6077 5450);
PAINT GREEN (-6077 5450);
DISPLAY INVISIBLE (-6077 5450);
FORCEADD TAP..1
(-6075 5500);
FORCEPROP 3 LASTPIN (-6125 5500) SIG_NAME M_D_CPU0_SA_DQ<30>
J 0
(-6115 5510);
DISPLAY 0.659574 (-6115 5510);
PAINT MONO (-6115 5510);
DISPLAY INVISIBLE (-6115 5510);
FORCEPROP 1 LASTPIN (-6125 5500) BN 30
J 0
(-6137 5508);
DISPLAY 0.489362 (-6137 5508);
PAINT GREEN (-6137 5508);
FORCEPROP 2 LAST CDS_LIB mstr_standard
J 0
(-6075 5500);
DISPLAY 0.723404 (-6075 5500);
PAINT MONO (-6075 5500);
DISPLAY INVISIBLE (-6075 5500);
FORCEPROP 1 LAST BODY_TYPE PLUMBING
J 0
(-6075 5550);
DISPLAY 0.872340 (-6075 5550);
PAINT GREEN (-6075 5550);
DISPLAY INVISIBLE (-6075 5550);
FORCEPROP 1 LAST HDL_TAP TRUE
J 0
(-5750 5375);
DISPLAY 0.872340 (-5750 5375);
DISPLAY INVISIBLE (-5750 5375);
FORCEPROP 1 LAST PATH I281
J 0
(-6077 5500);
DISPLAY 0.872340 (-6077 5500);
PAINT GREEN (-6077 5500);
DISPLAY INVISIBLE (-6077 5500);
FORCEADD TAP..1
(-6075 5550);
FORCEPROP 3 LASTPIN (-6125 5550) SIG_NAME M_D_CPU0_SA_DQ<31>
J 0
(-6115 5560);
DISPLAY 0.659574 (-6115 5560);
PAINT MONO (-6115 5560);
DISPLAY INVISIBLE (-6115 5560);
FORCEPROP 1 LASTPIN (-6125 5550) BN 31
J 0
(-6137 5558);
DISPLAY 0.489362 (-6137 5558);
PAINT GREEN (-6137 5558);
FORCEPROP 2 LAST CDS_LIB mstr_standard
J 0
(-6075 5550);
DISPLAY 0.723404 (-6075 5550);
PAINT MONO (-6075 5550);
DISPLAY INVISIBLE (-6075 5550);
FORCEPROP 1 LAST BODY_TYPE PLUMBING
J 0
(-6075 5600);
DISPLAY 0.872340 (-6075 5600);
PAINT GREEN (-6075 5600);
DISPLAY INVISIBLE (-6075 5600);
FORCEPROP 1 LAST HDL_TAP TRUE
J 0
(-5750 5425);
DISPLAY 0.872340 (-5750 5425);
DISPLAY INVISIBLE (-5750 5425);
FORCEPROP 1 LAST PATH I282
J 0
(-6077 5550);
DISPLAY 0.872340 (-6077 5550);
PAINT GREEN (-6077 5550);
DISPLAY INVISIBLE (-6077 5550);
FORCEADD OFFPAGE..3
(-5525 3950);
FORCEPROP 2 LAST $XR0 13 
J 0
(-5221 3950);
DISPLAY 0.638298 (-5221 3950);
PAINT MONO (-5221 3950);
FORCEPROP 2 LAST PATH I283
J 0
(-5200 4000);
DISPLAY 0.808511 (-5200 4000);
DISPLAY INVISIBLE (-5200 4000);
FORCEPROP 1 LAST COMMENT_BODY TRUE
J 0
(-5575 3850);
DISPLAY 0.872340 (-5575 3850);
PAINT GREEN (-5575 3850);
DISPLAY INVISIBLE (-5575 3850);
FORCEPROP 1 LAST OFFPAGE TRUE
J 0
(-5200 3825);
DISPLAY 0.872340 (-5200 3825);
PAINT GREEN (-5200 3825);
DISPLAY INVISIBLE (-5200 3825);
FORCEPROP 2 LAST CDS_LIB mstr_standard
J 0
(-5525 3950);
DISPLAY 0.723404 (-5525 3950);
PAINT MONO (-5525 3950);
DISPLAY INVISIBLE (-5525 3950);
FORCEADD OFFPAGE..3
(-5525 5600);
FORCEPROP 2 LAST $XR0 13 
J 0
(-5311 5600);
DISPLAY 0.638298 (-5311 5600);
PAINT MONO (-5311 5600);
FORCEPROP 2 LAST PATH I290
J 0
(-5300 5650);
DISPLAY 0.808511 (-5300 5650);
DISPLAY INVISIBLE (-5300 5650);
FORCEPROP 1 LAST COMMENT_BODY TRUE
J 0
(-5575 5500);
DISPLAY 0.872340 (-5575 5500);
PAINT GREEN (-5575 5500);
DISPLAY INVISIBLE (-5575 5500);
FORCEPROP 1 LAST OFFPAGE TRUE
J 0
(-5200 5475);
DISPLAY 0.872340 (-5200 5475);
PAINT GREEN (-5200 5475);
DISPLAY INVISIBLE (-5200 5475);
FORCEPROP 2 LAST CDS_LIB mstr_standard
J 0
(-5525 5600);
DISPLAY 0.723404 (-5525 5600);
PAINT MONO (-5525 5600);
DISPLAY INVISIBLE (-5525 5600);
FORCEADD GND..1
(-6450 1175);
FORCEPROP 3 LASTPIN (-6450 1225) SIG_NAME GND\g
J 0
(-6440 1235);
DISPLAY 0.659574 (-6440 1235);
PAINT MONO (-6440 1235);
DISPLAY INVISIBLE (-6440 1235);
FORCEPROP 1 LAST SIZE 1B
J 0
(-6375 1125);
DISPLAY 0.851064 (-6375 1125);
PAINT GREEN (-6375 1125);
DISPLAY INVISIBLE (-6375 1125);
FORCEPROP 2 LAST CDS_LIB mstr_symbols
J 0
(-6450 1175);
DISPLAY 0.808511 (-6450 1175);
DISPLAY INVISIBLE (-6450 1175);
FORCEPROP 2 LAST BOM_COST MEM
J 0
(-6550 1250);
DISPLAY 0.808511 (-6550 1250);
DISPLAY INVISIBLE (-6550 1250);
FORCEPROP 1 LAST BODY_TYPE PLUMBING
J 0
(-6495 1132);
DISPLAY 0.340426 (-6495 1132);
PAINT GREEN (-6495 1132);
DISPLAY INVISIBLE (-6495 1132);
FORCEPROP 1 LAST PATH I332
J 0
(-6375 1175);
DISPLAY 0.872340 (-6375 1175);
PAINT GREEN (-6375 1175);
DISPLAY INVISIBLE (-6375 1175);
FORCEPROP 1 LAST VOLTAGE 0.0
J 0
(-6495 1132);
DISPLAY 0.723404 (-6495 1132);
PAINT SKYBLUE (-6495 1132);
DISPLAY INVISIBLE (-6495 1132);
FORCEPROP 1 LAST HDL_POWER GND
J 0
(-6450 1325);
DISPLAY 0.851064 (-6450 1325);
PAINT GREEN (-6450 1325);
DISPLAY INVISIBLE (-6450 1325);
FORCEADD OFFPAGE..5
(-7225 1600);
FORCEPROP 2 LAST $XR0 88 
J 0
(-7449 1600);
DISPLAY 0.638298 (-7449 1600);
PAINT MONO (-7449 1600);
FORCEPROP 2 LAST PATH I333
J 0
(-7175 1675);
DISPLAY 0.808511 (-7175 1675);
DISPLAY INVISIBLE (-7175 1675);
FORCEPROP 1 LAST COMMENT_BODY TRUE
J 0
(-7125 1525);
DISPLAY 0.872340 (-7125 1525);
PAINT GREEN (-7125 1525);
DISPLAY INVISIBLE (-7125 1525);
FORCEPROP 1 LAST OFFPAGE TRUE
J 0
(-6900 1475);
DISPLAY 0.872340 (-6900 1475);
PAINT GREEN (-6900 1475);
DISPLAY INVISIBLE (-6900 1475);
FORCEPROP 2 LAST CDS_LIB mstr_standard
J 0
(-7225 1600);
DISPLAY 0.808511 (-7225 1600);
DISPLAY INVISIBLE (-7225 1600);
FORCEPROP 2 LAST BOM_COST MEM
J 0
(-7300 1675);
DISPLAY 0.808511 (-7300 1675);
DISPLAY INVISIBLE (-7300 1675);
FORCEADD OFFPAGE..1
(-8375 3050);
FORCEPROP 2 LAST $XR0 88 
J 0
(-8626 3050);
DISPLAY 0.638298 (-8626 3050);
PAINT MONO (-8626 3050);
FORCEPROP 2 LAST PATH I334
J 0
(-8325 3125);
DISPLAY 0.808511 (-8325 3125);
DISPLAY INVISIBLE (-8325 3125);
FORCEPROP 1 LAST COMMENT_BODY TRUE
J 0
(-8250 2950);
DISPLAY 0.872340 (-8250 2950);
PAINT GREEN (-8250 2950);
DISPLAY INVISIBLE (-8250 2950);
FORCEPROP 1 LAST OFFPAGE TRUE
J 0
(-8050 2925);
DISPLAY 0.872340 (-8050 2925);
PAINT GREEN (-8050 2925);
DISPLAY INVISIBLE (-8050 2925);
FORCEPROP 2 LAST CDS_LIB mstr_standard
J 0
(-8375 3050);
DISPLAY 0.808511 (-8375 3050);
DISPLAY INVISIBLE (-8375 3050);
FORCEADD Q_RES..2
(-6450 1425);
FORCEPROP 1 LAST LOCATION R763
J 0
(-6405 1550);
DISPLAY 0.489362 (-6405 1550);
PAINT SKYBLUE (-6405 1550);
FORCEPROP 0 LAST $SEC 1
J 0
(-6400 1600);
DISPLAY 0.680851 (-6400 1600);
PAINT MONO (-6400 1600);
DISPLAY INVISIBLE (-6400 1600);
FORCEPROP 0 LAST CDS_SEC 1
J 0
(-6400 1600);
DISPLAY 1.021277 (-6400 1600);
DISPLAY INVISIBLE (-6400 1600);
FORCEPROP 1 LASTPIN (-6450 1525) $PN 1
J 0
(-6445 1487);
DISPLAY 0.489362 (-6445 1487);
PAINT MONO (-6445 1487);
FORCEPROP 1 LASTPIN (-6450 1325) $PN 2
J 0
(-6445 1335);
DISPLAY 0.489362 (-6445 1335);
PAINT MONO (-6445 1335);
FORCEPROP 1 LAST WATTAGE 1/16W
J 0
(-6410 1400);
DISPLAY 0.489362 (-6410 1400);
PAINT SKYBLUE (-6410 1400);
FORCEPROP 1 LAST MATERIAL CHIP
J 0
(-6410 1350);
DISPLAY 0.489362 (-6410 1350);
PAINT SKYBLUE (-6410 1350);
FORCEPROP 1 LAST TOLERANCE 1%
J 0
(-6405 1450);
DISPLAY 0.489362 (-6405 1450);
PAINT SKYBLUE (-6405 1450);
FORCEPROP 1 LAST VALUE 35.7K
J 0
(-6405 1500);
DISPLAY 0.489362 (-6405 1500);
PAINT SKYBLUE (-6405 1500);
FORCEPROP 1 LAST PART_NUMBER CS33572FB01
J 0
(-6410 1300);
DISPLAY 0.489362 (-6410 1300);
PAINT SKYBLUE (-6410 1300);
FORCEPROP 1 LAST PACK_TYPE 0402LF
J 0
(-6410 1250);
DISPLAY 0.489362 (-6410 1250);
PAINT SKYBLUE (-6410 1250);
FORCEPROP 2 LAST CDS_LIB pure_quanta
J 0
(-6450 1425);
DISPLAY INVISIBLE (-6450 1425);
FORCEPROP 1 LAST PATH I349
J 0
(-6400 1600);
DISPLAY 0.978723 (-6400 1600);
PAINT WHITE (-6400 1600);
DISPLAY INVISIBLE (-6400 1600);
FORCEADD SCONN288_DDR506112002KQ..1
(-6925 3800);
FORCEPROP 1 LAST LOCATION J19
J 0
(-7375 5875);
DISPLAY 0.468085 (-7375 5875);
PAINT SKYBLUE (-7375 5875);
FORCEPROP 0 LAST $SEC 1
J 0
(-7375 6025);
DISPLAY 0.680851 (-7375 6025);
PAINT MONO (-7375 6025);
DISPLAY INVISIBLE (-7375 6025);
FORCEPROP 2 LAST CDS_SEC 1
J 0
(-7375 6025);
DISPLAY 1.021277 (-7375 6025);
DISPLAY INVISIBLE (-7375 6025);
FORCEPROP 0 LASTPIN (-7525 3200) $PN 62
J 2
(-7535 3210);
DISPLAY 0.680851 (-7535 3210);
PAINT MONO (-7535 3210);
FORCEPROP 0 LASTPIN (-7525 5250) $PN 66
J 2
(-7535 5260);
DISPLAY 0.680851 (-7535 5260);
PAINT MONO (-7535 5260);
FORCEPROP 0 LASTPIN (-7525 4850) $PN 76
J 2
(-7535 4860);
DISPLAY 0.680851 (-7535 4860);
PAINT MONO (-7535 4860);
FORCEPROP 0 LASTPIN (-7525 5300) $PN 211
J 2
(-7535 5310);
DISPLAY 0.680851 (-7535 5310);
PAINT MONO (-7535 5310);
FORCEPROP 0 LASTPIN (-7525 4900) $PN 221
J 2
(-7535 4910);
DISPLAY 0.680851 (-7535 4910);
PAINT MONO (-7535 4910);
FORCEPROP 0 LASTPIN (-7525 5350) $PN 68
J 2
(-7535 5360);
DISPLAY 0.680851 (-7535 5360);
PAINT MONO (-7535 5360);
FORCEPROP 0 LASTPIN (-7525 4950) $PN 78
J 2
(-7535 4960);
DISPLAY 0.680851 (-7535 4960);
PAINT MONO (-7535 4960);
FORCEPROP 0 LASTPIN (-7525 5400) $PN 213
J 2
(-7535 5410);
DISPLAY 0.680851 (-7535 5410);
PAINT MONO (-7535 5410);
FORCEPROP 0 LASTPIN (-7525 5000) $PN 223
J 2
(-7535 5010);
DISPLAY 0.680851 (-7535 5010);
PAINT MONO (-7535 5010);
FORCEPROP 0 LASTPIN (-7525 5450) $PN 70
J 2
(-7535 5460);
DISPLAY 0.680851 (-7535 5460);
PAINT MONO (-7535 5460);
FORCEPROP 0 LASTPIN (-7525 5050) $PN 80
J 2
(-7535 5060);
DISPLAY 0.680851 (-7535 5060);
PAINT MONO (-7535 5060);
FORCEPROP 0 LASTPIN (-7525 5500) $PN 215
J 2
(-7535 5510);
DISPLAY 0.680851 (-7535 5510);
PAINT MONO (-7535 5510);
FORCEPROP 0 LASTPIN (-7525 5100) $PN 225
J 2
(-7535 5110);
DISPLAY 0.680851 (-7535 5110);
PAINT MONO (-7535 5110);
FORCEPROP 0 LASTPIN (-7525 5550) $PN 72
J 2
(-7535 5560);
DISPLAY 0.680851 (-7535 5560);
PAINT MONO (-7535 5560);
FORCEPROP 0 LASTPIN (-7525 5150) $PN 82
J 2
(-7535 5160);
DISPLAY 0.680851 (-7535 5160);
PAINT MONO (-7535 5160);
FORCEPROP 0 LASTPIN (-7525 3800) $PN 51
J 2
(-7535 3810);
DISPLAY 0.680851 (-7535 3810);
PAINT MONO (-7535 3810);
FORCEPROP 0 LASTPIN (-7525 3350) $PN 96
J 2
(-7535 3360);
DISPLAY 0.680851 (-7535 3360);
PAINT MONO (-7535 3360);
FORCEPROP 0 LASTPIN (-7525 3850) $PN 53
J 2
(-7535 3860);
DISPLAY 0.680851 (-7535 3860);
PAINT MONO (-7535 3860);
FORCEPROP 0 LASTPIN (-7525 3400) $PN 98
J 2
(-7535 3410);
DISPLAY 0.680851 (-7535 3410);
PAINT MONO (-7535 3410);
FORCEPROP 0 LASTPIN (-7525 3900) $PN 196
J 2
(-7535 3910);
DISPLAY 0.680851 (-7535 3910);
PAINT MONO (-7535 3910);
FORCEPROP 0 LASTPIN (-7525 3450) $PN 241
J 2
(-7535 3460);
DISPLAY 0.680851 (-7535 3460);
PAINT MONO (-7535 3460);
FORCEPROP 0 LASTPIN (-7525 3950) $PN 198
J 2
(-7535 3960);
DISPLAY 0.680851 (-7535 3960);
PAINT MONO (-7535 3960);
FORCEPROP 0 LASTPIN (-7525 3500) $PN 243
J 2
(-7535 3510);
DISPLAY 0.680851 (-7535 3510);
PAINT MONO (-7535 3510);
FORCEPROP 0 LASTPIN (-7525 4000) $PN 58
J 2
(-7535 4010);
DISPLAY 0.680851 (-7535 4010);
PAINT MONO (-7535 4010);
FORCEPROP 0 LASTPIN (-7525 3550) $PN 89
J 2
(-7535 3560);
DISPLAY 0.680851 (-7535 3560);
PAINT MONO (-7535 3560);
FORCEPROP 0 LASTPIN (-7525 4050) $PN 60
J 2
(-7535 4060);
DISPLAY 0.680851 (-7535 4060);
PAINT MONO (-7535 4060);
FORCEPROP 0 LASTPIN (-7525 3600) $PN 91
J 2
(-7535 3610);
DISPLAY 0.680851 (-7535 3610);
PAINT MONO (-7535 3610);
FORCEPROP 0 LASTPIN (-7525 4100) $PN 203
J 2
(-7535 4110);
DISPLAY 0.680851 (-7535 4110);
PAINT MONO (-7535 4110);
FORCEPROP 0 LASTPIN (-7525 3650) $PN 234
J 2
(-7535 3660);
DISPLAY 0.680851 (-7535 3660);
PAINT MONO (-7535 3660);
FORCEPROP 0 LASTPIN (-7525 4150) $PN 205
J 2
(-7535 4160);
DISPLAY 0.680851 (-7535 4160);
PAINT MONO (-7535 4160);
FORCEPROP 0 LASTPIN (-7525 3700) $PN 236
J 2
(-7535 3710);
DISPLAY 0.680851 (-7535 3710);
PAINT MONO (-7535 3710);
FORCEPROP 0 LASTPIN (-7525 4250) $PN 218
J 2
(-7535 4260);
DISPLAY 0.680851 (-7535 4260);
PAINT MONO (-7535 4260);
FORCEPROP 0 LASTPIN (-7525 4300) $PN 217
J 2
(-7535 4310);
DISPLAY 0.680851 (-7535 4310);
PAINT MONO (-7535 4310);
FORCEPROP 0 LASTPIN (-7525 4550) $PN 64
J 2
(-7535 4560);
DISPLAY 0.680851 (-7535 4560);
PAINT MONO (-7535 4560);
FORCEPROP 0 LASTPIN (-7525 4400) $PN 84
J 2
(-7535 4410);
DISPLAY 0.680851 (-7535 4410);
PAINT MONO (-7535 4410);
FORCEPROP 0 LASTPIN (-7525 4600) $PN 209
J 2
(-7535 4610);
DISPLAY 0.680851 (-7535 4610);
PAINT MONO (-7535 4610);
FORCEPROP 0 LASTPIN (-7525 4450) $PN 229
J 2
(-7535 4460);
DISPLAY 0.680851 (-7535 4460);
PAINT MONO (-7535 4460);
FORCEPROP 0 LASTPIN (-6325 4000) $PN 7
J 0
(-6315 4010);
DISPLAY 0.680851 (-6315 4010);
PAINT MONO (-6315 4010);
FORCEPROP 0 LASTPIN (-6325 2350) $PN 100
J 0
(-6315 2360);
DISPLAY 0.680851 (-6315 2360);
PAINT MONO (-6315 2360);
FORCEPROP 0 LASTPIN (-6325 4050) $PN 9
J 0
(-6315 4060);
DISPLAY 0.680851 (-6315 4060);
PAINT MONO (-6315 4060);
FORCEPROP 0 LASTPIN (-6325 2400) $PN 102
J 0
(-6315 2410);
DISPLAY 0.680851 (-6315 2410);
PAINT MONO (-6315 2410);
FORCEPROP 0 LASTPIN (-6325 4100) $PN 152
J 0
(-6315 4110);
DISPLAY 0.680851 (-6315 4110);
PAINT MONO (-6315 4110);
FORCEPROP 0 LASTPIN (-6325 2450) $PN 245
J 0
(-6315 2460);
DISPLAY 0.680851 (-6315 2460);
PAINT MONO (-6315 2460);
FORCEPROP 0 LASTPIN (-6325 4150) $PN 154
J 0
(-6315 4160);
DISPLAY 0.680851 (-6315 4160);
PAINT MONO (-6315 4160);
FORCEPROP 0 LASTPIN (-6325 2500) $PN 247
J 0
(-6315 2510);
DISPLAY 0.680851 (-6315 2510);
PAINT MONO (-6315 2510);
FORCEPROP 0 LASTPIN (-6325 4200) $PN 14
J 0
(-6315 4210);
DISPLAY 0.680851 (-6315 4210);
PAINT MONO (-6315 4210);
FORCEPROP 0 LASTPIN (-6325 2550) $PN 107
J 0
(-6315 2560);
DISPLAY 0.680851 (-6315 2560);
PAINT MONO (-6315 2560);
FORCEPROP 0 LASTPIN (-6325 4250) $PN 16
J 0
(-6315 4260);
DISPLAY 0.680851 (-6315 4260);
PAINT MONO (-6315 4260);
FORCEPROP 0 LASTPIN (-6325 2600) $PN 109
J 0
(-6315 2610);
DISPLAY 0.680851 (-6315 2610);
PAINT MONO (-6315 2610);
FORCEPROP 0 LASTPIN (-6325 4300) $PN 159
J 0
(-6315 4310);
DISPLAY 0.680851 (-6315 4310);
PAINT MONO (-6315 4310);
FORCEPROP 0 LASTPIN (-6325 2650) $PN 252
J 0
(-6315 2660);
DISPLAY 0.680851 (-6315 2660);
PAINT MONO (-6315 2660);
FORCEPROP 0 LASTPIN (-6325 4350) $PN 161
J 0
(-6315 4360);
DISPLAY 0.680851 (-6315 4360);
PAINT MONO (-6315 4360);
FORCEPROP 0 LASTPIN (-6325 2700) $PN 254
J 0
(-6315 2710);
DISPLAY 0.680851 (-6315 2710);
PAINT MONO (-6315 2710);
FORCEPROP 0 LASTPIN (-6325 4400) $PN 18
J 0
(-6315 4410);
DISPLAY 0.680851 (-6315 4410);
PAINT MONO (-6315 4410);
FORCEPROP 0 LASTPIN (-6325 2750) $PN 111
J 0
(-6315 2760);
DISPLAY 0.680851 (-6315 2760);
PAINT MONO (-6315 2760);
FORCEPROP 0 LASTPIN (-6325 4450) $PN 20
J 0
(-6315 4460);
DISPLAY 0.680851 (-6315 4460);
PAINT MONO (-6315 4460);
FORCEPROP 0 LASTPIN (-6325 2800) $PN 113
J 0
(-6315 2810);
DISPLAY 0.680851 (-6315 2810);
PAINT MONO (-6315 2810);
FORCEPROP 0 LASTPIN (-6325 4500) $PN 163
J 0
(-6315 4510);
DISPLAY 0.680851 (-6315 4510);
PAINT MONO (-6315 4510);
FORCEPROP 0 LASTPIN (-6325 2850) $PN 256
J 0
(-6315 2860);
DISPLAY 0.680851 (-6315 2860);
PAINT MONO (-6315 2860);
FORCEPROP 0 LASTPIN (-6325 4550) $PN 165
J 0
(-6315 4560);
DISPLAY 0.680851 (-6315 4560);
PAINT MONO (-6315 4560);
FORCEPROP 0 LASTPIN (-6325 2900) $PN 258
J 0
(-6315 2910);
DISPLAY 0.680851 (-6315 2910);
PAINT MONO (-6315 2910);
FORCEPROP 0 LASTPIN (-6325 4600) $PN 25
J 0
(-6315 4610);
DISPLAY 0.680851 (-6315 4610);
PAINT MONO (-6315 4610);
FORCEPROP 0 LASTPIN (-6325 2950) $PN 118
J 0
(-6315 2960);
DISPLAY 0.680851 (-6315 2960);
PAINT MONO (-6315 2960);
FORCEPROP 0 LASTPIN (-6325 4650) $PN 27
J 0
(-6315 4660);
DISPLAY 0.680851 (-6315 4660);
PAINT MONO (-6315 4660);
FORCEPROP 0 LASTPIN (-6325 3000) $PN 120
J 0
(-6315 3010);
DISPLAY 0.680851 (-6315 3010);
PAINT MONO (-6315 3010);
FORCEPROP 0 LASTPIN (-6325 4700) $PN 170
J 0
(-6315 4710);
DISPLAY 0.680851 (-6315 4710);
PAINT MONO (-6315 4710);
FORCEPROP 0 LASTPIN (-6325 3050) $PN 263
J 0
(-6315 3060);
DISPLAY 0.680851 (-6315 3060);
PAINT MONO (-6315 3060);
FORCEPROP 0 LASTPIN (-6325 4750) $PN 172
J 0
(-6315 4760);
DISPLAY 0.680851 (-6315 4760);
PAINT MONO (-6315 4760);
FORCEPROP 0 LASTPIN (-6325 3100) $PN 265
J 0
(-6315 3110);
DISPLAY 0.680851 (-6315 3110);
PAINT MONO (-6315 3110);
FORCEPROP 0 LASTPIN (-6325 4800) $PN 29
J 0
(-6315 4810);
DISPLAY 0.680851 (-6315 4810);
PAINT MONO (-6315 4810);
FORCEPROP 0 LASTPIN (-6325 3150) $PN 122
J 0
(-6315 3160);
DISPLAY 0.680851 (-6315 3160);
PAINT MONO (-6315 3160);
FORCEPROP 0 LASTPIN (-6325 4850) $PN 31
J 0
(-6315 4860);
DISPLAY 0.680851 (-6315 4860);
PAINT MONO (-6315 4860);
FORCEPROP 0 LASTPIN (-6325 3200) $PN 124
J 0
(-6315 3210);
DISPLAY 0.680851 (-6315 3210);
PAINT MONO (-6315 3210);
FORCEPROP 0 LASTPIN (-6325 4900) $PN 174
J 0
(-6315 4910);
DISPLAY 0.680851 (-6315 4910);
PAINT MONO (-6315 4910);
FORCEPROP 0 LASTPIN (-6325 3250) $PN 267
J 0
(-6315 3260);
DISPLAY 0.680851 (-6315 3260);
PAINT MONO (-6315 3260);
FORCEPROP 0 LASTPIN (-6325 4950) $PN 176
J 0
(-6315 4960);
DISPLAY 0.680851 (-6315 4960);
PAINT MONO (-6315 4960);
FORCEPROP 0 LASTPIN (-6325 3300) $PN 269
J 0
(-6315 3310);
DISPLAY 0.680851 (-6315 3310);
PAINT MONO (-6315 3310);
FORCEPROP 0 LASTPIN (-6325 5000) $PN 36
J 0
(-6315 5010);
DISPLAY 0.680851 (-6315 5010);
PAINT MONO (-6315 5010);
FORCEPROP 0 LASTPIN (-6325 3350) $PN 129
J 0
(-6315 3360);
DISPLAY 0.680851 (-6315 3360);
PAINT MONO (-6315 3360);
FORCEPROP 0 LASTPIN (-6325 5050) $PN 38
J 0
(-6315 5060);
DISPLAY 0.680851 (-6315 5060);
PAINT MONO (-6315 5060);
FORCEPROP 0 LASTPIN (-6325 3400) $PN 131
J 0
(-6315 3410);
DISPLAY 0.680851 (-6315 3410);
PAINT MONO (-6315 3410);
FORCEPROP 0 LASTPIN (-6325 5100) $PN 181
J 0
(-6315 5110);
DISPLAY 0.680851 (-6315 5110);
PAINT MONO (-6315 5110);
FORCEPROP 0 LASTPIN (-6325 3450) $PN 274
J 0
(-6315 3460);
DISPLAY 0.680851 (-6315 3460);
PAINT MONO (-6315 3460);
FORCEPROP 0 LASTPIN (-6325 5150) $PN 183
J 0
(-6315 5160);
DISPLAY 0.680851 (-6315 5160);
PAINT MONO (-6315 5160);
FORCEPROP 0 LASTPIN (-6325 3500) $PN 276
J 0
(-6315 3510);
DISPLAY 0.680851 (-6315 3510);
PAINT MONO (-6315 3510);
FORCEPROP 0 LASTPIN (-6325 5200) $PN 40
J 0
(-6315 5210);
DISPLAY 0.680851 (-6315 5210);
PAINT MONO (-6315 5210);
FORCEPROP 0 LASTPIN (-6325 3550) $PN 133
J 0
(-6315 3560);
DISPLAY 0.680851 (-6315 3560);
PAINT MONO (-6315 3560);
FORCEPROP 0 LASTPIN (-6325 5250) $PN 42
J 0
(-6315 5260);
DISPLAY 0.680851 (-6315 5260);
PAINT MONO (-6315 5260);
FORCEPROP 0 LASTPIN (-6325 3600) $PN 135
J 0
(-6315 3610);
DISPLAY 0.680851 (-6315 3610);
PAINT MONO (-6315 3610);
FORCEPROP 0 LASTPIN (-6325 5300) $PN 185
J 0
(-6315 5310);
DISPLAY 0.680851 (-6315 5310);
PAINT MONO (-6315 5310);
FORCEPROP 0 LASTPIN (-6325 3650) $PN 278
J 0
(-6315 3660);
DISPLAY 0.680851 (-6315 3660);
PAINT MONO (-6315 3660);
FORCEPROP 0 LASTPIN (-6325 5350) $PN 187
J 0
(-6315 5360);
DISPLAY 0.680851 (-6315 5360);
PAINT MONO (-6315 5360);
FORCEPROP 0 LASTPIN (-6325 3700) $PN 280
J 0
(-6315 3710);
DISPLAY 0.680851 (-6315 3710);
PAINT MONO (-6315 3710);
FORCEPROP 0 LASTPIN (-6325 5400) $PN 47
J 0
(-6315 5410);
DISPLAY 0.680851 (-6315 5410);
PAINT MONO (-6315 5410);
FORCEPROP 0 LASTPIN (-6325 3750) $PN 140
J 0
(-6315 3760);
DISPLAY 0.680851 (-6315 3760);
PAINT MONO (-6315 3760);
FORCEPROP 0 LASTPIN (-6325 5450) $PN 49
J 0
(-6315 5460);
DISPLAY 0.680851 (-6315 5460);
PAINT MONO (-6315 5460);
FORCEPROP 0 LASTPIN (-6325 3800) $PN 142
J 0
(-6315 3810);
DISPLAY 0.680851 (-6315 3810);
PAINT MONO (-6315 3810);
FORCEPROP 0 LASTPIN (-6325 5500) $PN 192
J 0
(-6315 5510);
DISPLAY 0.680851 (-6315 5510);
PAINT MONO (-6315 5510);
FORCEPROP 0 LASTPIN (-6325 3850) $PN 285
J 0
(-6315 3860);
DISPLAY 0.680851 (-6315 3860);
PAINT MONO (-6315 3860);
FORCEPROP 0 LASTPIN (-6325 5550) $PN 194
J 0
(-6315 5560);
DISPLAY 0.680851 (-6315 5560);
PAINT MONO (-6315 5560);
FORCEPROP 0 LASTPIN (-6325 3900) $PN 287
J 0
(-6315 3910);
DISPLAY 0.680851 (-6315 3910);
PAINT MONO (-6315 3910);
FORCEPROP 0 LASTPIN (-7525 3050) $PN 148
J 2
(-7535 3060);
DISPLAY 0.680851 (-7535 3060);
PAINT MONO (-7535 3060);
FORCEPROP 0 LASTPIN (-7525 2950) $PN 4
J 2
(-7535 2960);
DISPLAY 0.680851 (-7535 2960);
PAINT MONO (-7535 2960);
FORCEPROP 0 LASTPIN (-7525 3000) $PN 5
J 2
(-7535 3010);
DISPLAY 0.680851 (-7535 3010);
PAINT MONO (-7535 3010);
FORCEPROP 0 LASTPIN (-7525 2150) $PN 86
J 2
(-7535 2160);
DISPLAY 0.680851 (-7535 2160);
PAINT MONO (-7535 2160);
FORCEPROP 0 LASTPIN (-7525 2100) $PN 87
J 2
(-7535 2110);
DISPLAY 0.680851 (-7535 2110);
PAINT MONO (-7535 2110);
FORCEPROP 0 LASTPIN (-7525 4750) $PN 74
J 2
(-7535 4760);
DISPLAY 0.680851 (-7535 4760);
PAINT MONO (-7535 4760);
FORCEPROP 0 LASTPIN (-7525 4700) $PN 227
J 2
(-7535 4710);
DISPLAY 0.680851 (-7535 4710);
PAINT MONO (-7535 4710);
FORCEPROP 0 LASTPIN (-7525 2700) $PN 147
J 2
(-7535 2710);
DISPLAY 0.680851 (-7535 2710);
PAINT MONO (-7535 2710);
FORCEPROP 0 LASTPIN (-7525 3250) $PN 207
J 2
(-7535 3260);
DISPLAY 0.680851 (-7535 3260);
PAINT MONO (-7535 3260);
FORCEPROP 0 LASTPIN (-7525 2300) $PN 2
J 2
(-7535 2310);
DISPLAY 0.680851 (-7535 2310);
PAINT MONO (-7535 2310);
FORCEPROP 0 LASTPIN (-7525 2350) $PN 144
J 2
(-7535 2360);
DISPLAY 0.680851 (-7535 2360);
PAINT MONO (-7535 2360);
FORCEPROP 0 LASTPIN (-7525 2400) $PN 149
J 2
(-7535 2410);
DISPLAY 0.680851 (-7535 2410);
PAINT MONO (-7535 2410);
FORCEPROP 0 LASTPIN (-7525 2450) $PN 150
J 2
(-7535 2460);
DISPLAY 0.680851 (-7535 2460);
PAINT MONO (-7535 2460);
FORCEPROP 0 LASTPIN (-7525 2500) $PN 220
J 2
(-7535 2510);
DISPLAY 0.680851 (-7535 2510);
PAINT MONO (-7535 2510);
FORCEPROP 0 LASTPIN (-7525 2550) $PN 231
J 2
(-7535 2560);
DISPLAY 0.680851 (-7535 2560);
PAINT MONO (-7535 2560);
FORCEPROP 0 LASTPIN (-7525 2600) $PN 232
J 2
(-7535 2610);
DISPLAY 0.680851 (-7535 2610);
PAINT MONO (-7535 2610);
FORCEPROP 0 LASTPIN (-7525 3100) $PN 3
J 2
(-7535 3110);
DISPLAY 0.680851 (-7535 3110);
PAINT MONO (-7535 3110);
FORCEPROP 2 LAST PART_TYPE SMLF
J 0
(-7375 5975);
DISPLAY 1.021277 (-7375 5975);
FORCEPROP 1 LAST MATERIAL IO
J 0
(-7375 5725);
DISPLAY 0.468085 (-7375 5725);
PAINT SKYBLUE (-7375 5725);
FORCEPROP 2 LAST VALUE SCONN288_DDR506112002KQ
J 0
(-7375 5925);
DISPLAY 0.489362 (-7375 5925);
PAINT SKYBLUE (-7375 5925);
FORCEPROP 1 LAST PART_NUMBER DFHST8FS479
J 0
(-7375 5800);
DISPLAY 0.468085 (-7375 5800);
PAINT SKYBLUE (-7375 5800);
FORCEPROP 1 LAST CDS_LMAN_SYM_OUTLINE -450,1900,450,-1850
J 0
(-6925 3800);
DISPLAY 0.468085 (-6925 3800);
PAINT GREEN (-6925 3800);
DISPLAY INVISIBLE (-6925 3800);
FORCEPROP 1 LAST PATH I350
J 0
(-6925 3800);
DISPLAY 0.723404 (-6925 3800);
PAINT GREEN (-6925 3800);
DISPLAY INVISIBLE (-6925 3800);
FORCEPROP 1 LAST NEEDS_NO_SIZE TRUE
J 0
(-6925 3800);
DISPLAY 0.723404 (-6925 3800);
PAINT GREEN (-6925 3800);
DISPLAY INVISIBLE (-6925 3800);
FORCEPROP 2 LAST CDS_LIB pure_quanta
J 0
(-6925 3800);
DISPLAY INVISIBLE (-6925 3800);
FORCEADD SCONN288_DDR506112002KQ..3
(-1350 3700);
FORCEPROP 1 LAST LOCATION J19
J 0
(-1800 5675);
DISPLAY 0.468085 (-1800 5675);
PAINT SKYBLUE (-1800 5675);
FORCEPROP 0 LAST $SEC 3
J 0
(-1800 5825);
DISPLAY 0.680851 (-1800 5825);
PAINT MONO (-1800 5825);
DISPLAY INVISIBLE (-1800 5825);
FORCEPROP 2 LAST CDS_SEC 3
J 0
(-1800 5825);
DISPLAY 1.021277 (-1800 5825);
DISPLAY INVISIBLE (-1800 5825);
FORCEPROP 0 LASTPIN (-750 2100) $PN G1
J 0
(-740 2110);
DISPLAY 0.680851 (-740 2110);
PAINT MONO (-740 2110);
FORCEPROP 0 LASTPIN (-750 2050) $PN G2
J 0
(-740 2060);
DISPLAY 0.680851 (-740 2060);
PAINT MONO (-740 2060);
FORCEPROP 0 LASTPIN (-750 2000) $PN G3
J 0
(-740 2010);
DISPLAY 0.680851 (-740 2010);
PAINT MONO (-740 2010);
FORCEPROP 0 LASTPIN (-1950 5250) $PN 1
J 2
(-1960 5260);
DISPLAY 0.680851 (-1960 5260);
PAINT MONO (-1960 5260);
FORCEPROP 0 LASTPIN (-1950 5300) $PN 145
J 2
(-1960 5310);
DISPLAY 0.680851 (-1960 5310);
PAINT MONO (-1960 5310);
FORCEPROP 0 LASTPIN (-1950 5350) $PN 146
J 2
(-1960 5360);
DISPLAY 0.680851 (-1960 5360);
PAINT MONO (-1960 5360);
FORCEPROP 0 LASTPIN (-750 2200) $PN 6
J 0
(-740 2210);
DISPLAY 0.680851 (-740 2210);
PAINT MONO (-740 2210);
FORCEPROP 0 LASTPIN (-750 2250) $PN 8
J 0
(-740 2260);
DISPLAY 0.680851 (-740 2260);
PAINT MONO (-740 2260);
FORCEPROP 0 LASTPIN (-750 2300) $PN 10
J 0
(-740 2310);
DISPLAY 0.680851 (-740 2310);
PAINT MONO (-740 2310);
FORCEPROP 0 LASTPIN (-750 2350) $PN 13
J 0
(-740 2360);
DISPLAY 0.680851 (-740 2360);
PAINT MONO (-740 2360);
FORCEPROP 0 LASTPIN (-750 2400) $PN 15
J 0
(-740 2410);
DISPLAY 0.680851 (-740 2410);
PAINT MONO (-740 2410);
FORCEPROP 0 LASTPIN (-750 2450) $PN 17
J 0
(-740 2460);
DISPLAY 0.680851 (-740 2460);
PAINT MONO (-740 2460);
FORCEPROP 0 LASTPIN (-750 2500) $PN 19
J 0
(-740 2510);
DISPLAY 0.680851 (-740 2510);
PAINT MONO (-740 2510);
FORCEPROP 0 LASTPIN (-750 2550) $PN 21
J 0
(-740 2560);
DISPLAY 0.680851 (-740 2560);
PAINT MONO (-740 2560);
FORCEPROP 0 LASTPIN (-750 2600) $PN 24
J 0
(-740 2610);
DISPLAY 0.680851 (-740 2610);
PAINT MONO (-740 2610);
FORCEPROP 0 LASTPIN (-750 2650) $PN 26
J 0
(-740 2660);
DISPLAY 0.680851 (-740 2660);
PAINT MONO (-740 2660);
FORCEPROP 0 LASTPIN (-750 2700) $PN 28
J 0
(-740 2710);
DISPLAY 0.680851 (-740 2710);
PAINT MONO (-740 2710);
FORCEPROP 0 LASTPIN (-750 2750) $PN 30
J 0
(-740 2760);
DISPLAY 0.680851 (-740 2760);
PAINT MONO (-740 2760);
FORCEPROP 0 LASTPIN (-750 2800) $PN 32
J 0
(-740 2810);
DISPLAY 0.680851 (-740 2810);
PAINT MONO (-740 2810);
FORCEPROP 0 LASTPIN (-750 2850) $PN 35
J 0
(-740 2860);
DISPLAY 0.680851 (-740 2860);
PAINT MONO (-740 2860);
FORCEPROP 0 LASTPIN (-750 2900) $PN 37
J 0
(-740 2910);
DISPLAY 0.680851 (-740 2910);
PAINT MONO (-740 2910);
FORCEPROP 0 LASTPIN (-750 2950) $PN 39
J 0
(-740 2960);
DISPLAY 0.680851 (-740 2960);
PAINT MONO (-740 2960);
FORCEPROP 0 LASTPIN (-750 3000) $PN 41
J 0
(-740 3010);
DISPLAY 0.680851 (-740 3010);
PAINT MONO (-740 3010);
FORCEPROP 0 LASTPIN (-750 3050) $PN 43
J 0
(-740 3060);
DISPLAY 0.680851 (-740 3060);
PAINT MONO (-740 3060);
FORCEPROP 0 LASTPIN (-750 3100) $PN 46
J 0
(-740 3110);
DISPLAY 0.680851 (-740 3110);
PAINT MONO (-740 3110);
FORCEPROP 0 LASTPIN (-750 3150) $PN 48
J 0
(-740 3160);
DISPLAY 0.680851 (-740 3160);
PAINT MONO (-740 3160);
FORCEPROP 0 LASTPIN (-750 3200) $PN 50
J 0
(-740 3210);
DISPLAY 0.680851 (-740 3210);
PAINT MONO (-740 3210);
FORCEPROP 0 LASTPIN (-750 3250) $PN 52
J 0
(-740 3260);
DISPLAY 0.680851 (-740 3260);
PAINT MONO (-740 3260);
FORCEPROP 0 LASTPIN (-750 3300) $PN 54
J 0
(-740 3310);
DISPLAY 0.680851 (-740 3310);
PAINT MONO (-740 3310);
FORCEPROP 0 LASTPIN (-750 3350) $PN 57
J 0
(-740 3360);
DISPLAY 0.680851 (-740 3360);
PAINT MONO (-740 3360);
FORCEPROP 0 LASTPIN (-750 3400) $PN 59
J 0
(-740 3410);
DISPLAY 0.680851 (-740 3410);
PAINT MONO (-740 3410);
FORCEPROP 0 LASTPIN (-750 3450) $PN 61
J 0
(-740 3460);
DISPLAY 0.680851 (-740 3460);
PAINT MONO (-740 3460);
FORCEPROP 0 LASTPIN (-750 3500) $PN 63
J 0
(-740 3510);
DISPLAY 0.680851 (-740 3510);
PAINT MONO (-740 3510);
FORCEPROP 0 LASTPIN (-750 3550) $PN 65
J 0
(-740 3560);
DISPLAY 0.680851 (-740 3560);
PAINT MONO (-740 3560);
FORCEPROP 0 LASTPIN (-750 3600) $PN 67
J 0
(-740 3610);
DISPLAY 0.680851 (-740 3610);
PAINT MONO (-740 3610);
FORCEPROP 0 LASTPIN (-750 3650) $PN 69
J 0
(-740 3660);
DISPLAY 0.680851 (-740 3660);
PAINT MONO (-740 3660);
FORCEPROP 0 LASTPIN (-750 3700) $PN 71
J 0
(-740 3710);
DISPLAY 0.680851 (-740 3710);
PAINT MONO (-740 3710);
FORCEPROP 0 LASTPIN (-750 3750) $PN 73
J 0
(-740 3760);
DISPLAY 0.680851 (-740 3760);
PAINT MONO (-740 3760);
FORCEPROP 0 LASTPIN (-750 3800) $PN 75
J 0
(-740 3810);
DISPLAY 0.680851 (-740 3810);
PAINT MONO (-740 3810);
FORCEPROP 0 LASTPIN (-750 3850) $PN 77
J 0
(-740 3860);
DISPLAY 0.680851 (-740 3860);
PAINT MONO (-740 3860);
FORCEPROP 0 LASTPIN (-750 3900) $PN 79
J 0
(-740 3910);
DISPLAY 0.680851 (-740 3910);
PAINT MONO (-740 3910);
FORCEPROP 0 LASTPIN (-750 3950) $PN 81
J 0
(-740 3960);
DISPLAY 0.680851 (-740 3960);
PAINT MONO (-740 3960);
FORCEPROP 0 LASTPIN (-750 4000) $PN 83
J 0
(-740 4010);
DISPLAY 0.680851 (-740 4010);
PAINT MONO (-740 4010);
FORCEPROP 0 LASTPIN (-750 4050) $PN 85
J 0
(-740 4060);
DISPLAY 0.680851 (-740 4060);
PAINT MONO (-740 4060);
FORCEPROP 0 LASTPIN (-750 4100) $PN 88
J 0
(-740 4110);
DISPLAY 0.680851 (-740 4110);
PAINT MONO (-740 4110);
FORCEPROP 0 LASTPIN (-750 4150) $PN 90
J 0
(-740 4160);
DISPLAY 0.680851 (-740 4160);
PAINT MONO (-740 4160);
FORCEPROP 0 LASTPIN (-750 4200) $PN 92
J 0
(-740 4210);
DISPLAY 0.680851 (-740 4210);
PAINT MONO (-740 4210);
FORCEPROP 0 LASTPIN (-750 4250) $PN 95
J 0
(-740 4260);
DISPLAY 0.680851 (-740 4260);
PAINT MONO (-740 4260);
FORCEPROP 0 LASTPIN (-750 4300) $PN 97
J 0
(-740 4310);
DISPLAY 0.680851 (-740 4310);
PAINT MONO (-740 4310);
FORCEPROP 0 LASTPIN (-750 4350) $PN 99
J 0
(-740 4360);
DISPLAY 0.680851 (-740 4360);
PAINT MONO (-740 4360);
FORCEPROP 0 LASTPIN (-750 4400) $PN 101
J 0
(-740 4410);
DISPLAY 0.680851 (-740 4410);
PAINT MONO (-740 4410);
FORCEPROP 0 LASTPIN (-750 4450) $PN 103
J 0
(-740 4460);
DISPLAY 0.680851 (-740 4460);
PAINT MONO (-740 4460);
FORCEPROP 0 LASTPIN (-750 4500) $PN 106
J 0
(-740 4510);
DISPLAY 0.680851 (-740 4510);
PAINT MONO (-740 4510);
FORCEPROP 0 LASTPIN (-750 4550) $PN 108
J 0
(-740 4560);
DISPLAY 0.680851 (-740 4560);
PAINT MONO (-740 4560);
FORCEPROP 0 LASTPIN (-750 4600) $PN 110
J 0
(-740 4610);
DISPLAY 0.680851 (-740 4610);
PAINT MONO (-740 4610);
FORCEPROP 0 LASTPIN (-750 4650) $PN 112
J 0
(-740 4660);
DISPLAY 0.680851 (-740 4660);
PAINT MONO (-740 4660);
FORCEPROP 0 LASTPIN (-750 4700) $PN 114
J 0
(-740 4710);
DISPLAY 0.680851 (-740 4710);
PAINT MONO (-740 4710);
FORCEPROP 0 LASTPIN (-750 4750) $PN 117
J 0
(-740 4760);
DISPLAY 0.680851 (-740 4760);
PAINT MONO (-740 4760);
FORCEPROP 0 LASTPIN (-750 4800) $PN 119
J 0
(-740 4810);
DISPLAY 0.680851 (-740 4810);
PAINT MONO (-740 4810);
FORCEPROP 0 LASTPIN (-750 4850) $PN 121
J 0
(-740 4860);
DISPLAY 0.680851 (-740 4860);
PAINT MONO (-740 4860);
FORCEPROP 0 LASTPIN (-750 4900) $PN 123
J 0
(-740 4910);
DISPLAY 0.680851 (-740 4910);
PAINT MONO (-740 4910);
FORCEPROP 0 LASTPIN (-750 4950) $PN 125
J 0
(-740 4960);
DISPLAY 0.680851 (-740 4960);
PAINT MONO (-740 4960);
FORCEPROP 0 LASTPIN (-750 5000) $PN 128
J 0
(-740 5010);
DISPLAY 0.680851 (-740 5010);
PAINT MONO (-740 5010);
FORCEPROP 0 LASTPIN (-750 5050) $PN 130
J 0
(-740 5060);
DISPLAY 0.680851 (-740 5060);
PAINT MONO (-740 5060);
FORCEPROP 0 LASTPIN (-750 5100) $PN 132
J 0
(-740 5110);
DISPLAY 0.680851 (-740 5110);
PAINT MONO (-740 5110);
FORCEPROP 0 LASTPIN (-750 5150) $PN 134
J 0
(-740 5160);
DISPLAY 0.680851 (-740 5160);
PAINT MONO (-740 5160);
FORCEPROP 0 LASTPIN (-750 5200) $PN 136
J 0
(-740 5210);
DISPLAY 0.680851 (-740 5210);
PAINT MONO (-740 5210);
FORCEPROP 0 LASTPIN (-750 5250) $PN 139
J 0
(-740 5260);
DISPLAY 0.680851 (-740 5260);
PAINT MONO (-740 5260);
FORCEPROP 0 LASTPIN (-750 5300) $PN 141
J 0
(-740 5310);
DISPLAY 0.680851 (-740 5310);
PAINT MONO (-740 5310);
FORCEPROP 0 LASTPIN (-750 5350) $PN 143
J 0
(-740 5360);
DISPLAY 0.680851 (-740 5360);
PAINT MONO (-740 5360);
FORCEPROP 0 LASTPIN (-1950 2100) $PN 151
J 2
(-1960 2110);
DISPLAY 0.680851 (-1960 2110);
PAINT MONO (-1960 2110);
FORCEPROP 0 LASTPIN (-1950 2150) $PN 153
J 2
(-1960 2160);
DISPLAY 0.680851 (-1960 2160);
PAINT MONO (-1960 2160);
FORCEPROP 0 LASTPIN (-1950 2200) $PN 155
J 2
(-1960 2210);
DISPLAY 0.680851 (-1960 2210);
PAINT MONO (-1960 2210);
FORCEPROP 0 LASTPIN (-1950 2250) $PN 158
J 2
(-1960 2260);
DISPLAY 0.680851 (-1960 2260);
PAINT MONO (-1960 2260);
FORCEPROP 0 LASTPIN (-1950 2300) $PN 160
J 2
(-1960 2310);
DISPLAY 0.680851 (-1960 2310);
PAINT MONO (-1960 2310);
FORCEPROP 0 LASTPIN (-1950 2350) $PN 162
J 2
(-1960 2360);
DISPLAY 0.680851 (-1960 2360);
PAINT MONO (-1960 2360);
FORCEPROP 0 LASTPIN (-1950 2400) $PN 164
J 2
(-1960 2410);
DISPLAY 0.680851 (-1960 2410);
PAINT MONO (-1960 2410);
FORCEPROP 0 LASTPIN (-1950 2450) $PN 166
J 2
(-1960 2460);
DISPLAY 0.680851 (-1960 2460);
PAINT MONO (-1960 2460);
FORCEPROP 0 LASTPIN (-1950 2500) $PN 169
J 2
(-1960 2510);
DISPLAY 0.680851 (-1960 2510);
PAINT MONO (-1960 2510);
FORCEPROP 0 LASTPIN (-1950 2550) $PN 171
J 2
(-1960 2560);
DISPLAY 0.680851 (-1960 2560);
PAINT MONO (-1960 2560);
FORCEPROP 0 LASTPIN (-1950 2600) $PN 173
J 2
(-1960 2610);
DISPLAY 0.680851 (-1960 2610);
PAINT MONO (-1960 2610);
FORCEPROP 0 LASTPIN (-1950 2650) $PN 175
J 2
(-1960 2660);
DISPLAY 0.680851 (-1960 2660);
PAINT MONO (-1960 2660);
FORCEPROP 0 LASTPIN (-1950 2700) $PN 177
J 2
(-1960 2710);
DISPLAY 0.680851 (-1960 2710);
PAINT MONO (-1960 2710);
FORCEPROP 0 LASTPIN (-1950 2750) $PN 180
J 2
(-1960 2760);
DISPLAY 0.680851 (-1960 2760);
PAINT MONO (-1960 2760);
FORCEPROP 0 LASTPIN (-1950 2800) $PN 182
J 2
(-1960 2810);
DISPLAY 0.680851 (-1960 2810);
PAINT MONO (-1960 2810);
FORCEPROP 0 LASTPIN (-1950 2850) $PN 184
J 2
(-1960 2860);
DISPLAY 0.680851 (-1960 2860);
PAINT MONO (-1960 2860);
FORCEPROP 0 LASTPIN (-1950 2900) $PN 186
J 2
(-1960 2910);
DISPLAY 0.680851 (-1960 2910);
PAINT MONO (-1960 2910);
FORCEPROP 0 LASTPIN (-1950 2950) $PN 188
J 2
(-1960 2960);
DISPLAY 0.680851 (-1960 2960);
PAINT MONO (-1960 2960);
FORCEPROP 0 LASTPIN (-1950 3000) $PN 191
J 2
(-1960 3010);
DISPLAY 0.680851 (-1960 3010);
PAINT MONO (-1960 3010);
FORCEPROP 0 LASTPIN (-1950 3050) $PN 193
J 2
(-1960 3060);
DISPLAY 0.680851 (-1960 3060);
PAINT MONO (-1960 3060);
FORCEPROP 0 LASTPIN (-1950 3100) $PN 195
J 2
(-1960 3110);
DISPLAY 0.680851 (-1960 3110);
PAINT MONO (-1960 3110);
FORCEPROP 0 LASTPIN (-1950 3150) $PN 197
J 2
(-1960 3160);
DISPLAY 0.680851 (-1960 3160);
PAINT MONO (-1960 3160);
FORCEPROP 0 LASTPIN (-1950 3200) $PN 199
J 2
(-1960 3210);
DISPLAY 0.680851 (-1960 3210);
PAINT MONO (-1960 3210);
FORCEPROP 0 LASTPIN (-1950 3250) $PN 202
J 2
(-1960 3260);
DISPLAY 0.680851 (-1960 3260);
PAINT MONO (-1960 3260);
FORCEPROP 0 LASTPIN (-1950 3300) $PN 204
J 2
(-1960 3310);
DISPLAY 0.680851 (-1960 3310);
PAINT MONO (-1960 3310);
FORCEPROP 0 LASTPIN (-1950 3350) $PN 206
J 2
(-1960 3360);
DISPLAY 0.680851 (-1960 3360);
PAINT MONO (-1960 3360);
FORCEPROP 0 LASTPIN (-1950 3400) $PN 208
J 2
(-1960 3410);
DISPLAY 0.680851 (-1960 3410);
PAINT MONO (-1960 3410);
FORCEPROP 0 LASTPIN (-1950 3450) $PN 210
J 2
(-1960 3460);
DISPLAY 0.680851 (-1960 3460);
PAINT MONO (-1960 3460);
FORCEPROP 0 LASTPIN (-1950 3500) $PN 212
J 2
(-1960 3510);
DISPLAY 0.680851 (-1960 3510);
PAINT MONO (-1960 3510);
FORCEPROP 0 LASTPIN (-1950 3550) $PN 214
J 2
(-1960 3560);
DISPLAY 0.680851 (-1960 3560);
PAINT MONO (-1960 3560);
FORCEPROP 0 LASTPIN (-1950 3600) $PN 216
J 2
(-1960 3610);
DISPLAY 0.680851 (-1960 3610);
PAINT MONO (-1960 3610);
FORCEPROP 0 LASTPIN (-1950 3650) $PN 219
J 2
(-1960 3660);
DISPLAY 0.680851 (-1960 3660);
PAINT MONO (-1960 3660);
FORCEPROP 0 LASTPIN (-1950 3700) $PN 222
J 2
(-1960 3710);
DISPLAY 0.680851 (-1960 3710);
PAINT MONO (-1960 3710);
FORCEPROP 0 LASTPIN (-1950 3750) $PN 224
J 2
(-1960 3760);
DISPLAY 0.680851 (-1960 3760);
PAINT MONO (-1960 3760);
FORCEPROP 0 LASTPIN (-1950 3800) $PN 226
J 2
(-1960 3810);
DISPLAY 0.680851 (-1960 3810);
PAINT MONO (-1960 3810);
FORCEPROP 0 LASTPIN (-1950 3850) $PN 228
J 2
(-1960 3860);
DISPLAY 0.680851 (-1960 3860);
PAINT MONO (-1960 3860);
FORCEPROP 0 LASTPIN (-1950 3900) $PN 230
J 2
(-1960 3910);
DISPLAY 0.680851 (-1960 3910);
PAINT MONO (-1960 3910);
FORCEPROP 0 LASTPIN (-1950 3950) $PN 233
J 2
(-1960 3960);
DISPLAY 0.680851 (-1960 3960);
PAINT MONO (-1960 3960);
FORCEPROP 0 LASTPIN (-1950 4000) $PN 235
J 2
(-1960 4010);
DISPLAY 0.680851 (-1960 4010);
PAINT MONO (-1960 4010);
FORCEPROP 0 LASTPIN (-1950 4050) $PN 237
J 2
(-1960 4060);
DISPLAY 0.680851 (-1960 4060);
PAINT MONO (-1960 4060);
FORCEPROP 0 LASTPIN (-1950 4100) $PN 240
J 2
(-1960 4110);
DISPLAY 0.680851 (-1960 4110);
PAINT MONO (-1960 4110);
FORCEPROP 0 LASTPIN (-1950 4150) $PN 242
J 2
(-1960 4160);
DISPLAY 0.680851 (-1960 4160);
PAINT MONO (-1960 4160);
FORCEPROP 0 LASTPIN (-1950 4200) $PN 244
J 2
(-1960 4210);
DISPLAY 0.680851 (-1960 4210);
PAINT MONO (-1960 4210);
FORCEPROP 0 LASTPIN (-1950 4250) $PN 246
J 2
(-1960 4260);
DISPLAY 0.680851 (-1960 4260);
PAINT MONO (-1960 4260);
FORCEPROP 0 LASTPIN (-1950 4300) $PN 248
J 2
(-1960 4310);
DISPLAY 0.680851 (-1960 4310);
PAINT MONO (-1960 4310);
FORCEPROP 0 LASTPIN (-1950 4350) $PN 251
J 2
(-1960 4360);
DISPLAY 0.680851 (-1960 4360);
PAINT MONO (-1960 4360);
FORCEPROP 0 LASTPIN (-1950 4400) $PN 253
J 2
(-1960 4410);
DISPLAY 0.680851 (-1960 4410);
PAINT MONO (-1960 4410);
FORCEPROP 0 LASTPIN (-1950 4450) $PN 255
J 2
(-1960 4460);
DISPLAY 0.680851 (-1960 4460);
PAINT MONO (-1960 4460);
FORCEPROP 0 LASTPIN (-1950 4500) $PN 257
J 2
(-1960 4510);
DISPLAY 0.680851 (-1960 4510);
PAINT MONO (-1960 4510);
FORCEPROP 0 LASTPIN (-1950 4550) $PN 259
J 2
(-1960 4560);
DISPLAY 0.680851 (-1960 4560);
PAINT MONO (-1960 4560);
FORCEPROP 0 LASTPIN (-1950 4600) $PN 262
J 2
(-1960 4610);
DISPLAY 0.680851 (-1960 4610);
PAINT MONO (-1960 4610);
FORCEPROP 0 LASTPIN (-1950 4650) $PN 264
J 2
(-1960 4660);
DISPLAY 0.680851 (-1960 4660);
PAINT MONO (-1960 4660);
FORCEPROP 0 LASTPIN (-1950 4700) $PN 266
J 2
(-1960 4710);
DISPLAY 0.680851 (-1960 4710);
PAINT MONO (-1960 4710);
FORCEPROP 0 LASTPIN (-1950 4750) $PN 268
J 2
(-1960 4760);
DISPLAY 0.680851 (-1960 4760);
PAINT MONO (-1960 4760);
FORCEPROP 0 LASTPIN (-1950 4800) $PN 270
J 2
(-1960 4810);
DISPLAY 0.680851 (-1960 4810);
PAINT MONO (-1960 4810);
FORCEPROP 0 LASTPIN (-1950 4850) $PN 273
J 2
(-1960 4860);
DISPLAY 0.680851 (-1960 4860);
PAINT MONO (-1960 4860);
FORCEPROP 0 LASTPIN (-1950 4900) $PN 275
J 2
(-1960 4910);
DISPLAY 0.680851 (-1960 4910);
PAINT MONO (-1960 4910);
FORCEPROP 0 LASTPIN (-1950 4950) $PN 277
J 2
(-1960 4960);
DISPLAY 0.680851 (-1960 4960);
PAINT MONO (-1960 4960);
FORCEPROP 0 LASTPIN (-1950 5000) $PN 279
J 2
(-1960 5010);
DISPLAY 0.680851 (-1960 5010);
PAINT MONO (-1960 5010);
FORCEPROP 0 LASTPIN (-1950 5050) $PN 281
J 2
(-1960 5060);
DISPLAY 0.680851 (-1960 5060);
PAINT MONO (-1960 5060);
FORCEPROP 0 LASTPIN (-1950 5100) $PN 284
J 2
(-1960 5110);
DISPLAY 0.680851 (-1960 5110);
PAINT MONO (-1960 5110);
FORCEPROP 0 LASTPIN (-1950 5150) $PN 286
J 2
(-1960 5160);
DISPLAY 0.680851 (-1960 5160);
PAINT MONO (-1960 5160);
FORCEPROP 0 LASTPIN (-1950 5200) $PN 288
J 2
(-1960 5210);
DISPLAY 0.680851 (-1960 5210);
PAINT MONO (-1960 5210);
FORCEPROP 2 LAST VALUE SCONN288_DDR506112002KQ
J 0
(-1800 5725);
DISPLAY 0.489362 (-1800 5725);
PAINT SKYBLUE (-1800 5725);
FORCEPROP 2 LAST PART_TYPE SMLF
J 0
(-1800 5775);
DISPLAY 1.021277 (-1800 5775);
FORCEPROP 1 LAST MATERIAL IO
J 0
(-1800 5525);
DISPLAY 0.468085 (-1800 5525);
PAINT SKYBLUE (-1800 5525);
FORCEPROP 1 LAST PART_NUMBER DFHST8FS479
J 0
(-1800 5600);
DISPLAY 0.468085 (-1800 5600);
PAINT SKYBLUE (-1800 5600);
FORCEPROP 1 LAST CDS_LMAN_SYM_OUTLINE -450,1800,450,-1750
J 0
(-1350 3700);
DISPLAY 0.468085 (-1350 3700);
PAINT GREEN (-1350 3700);
DISPLAY INVISIBLE (-1350 3700);
FORCEPROP 1 LAST PATH I352
J 0
(-1350 3700);
DISPLAY 0.723404 (-1350 3700);
PAINT GREEN (-1350 3700);
DISPLAY INVISIBLE (-1350 3700);
FORCEPROP 1 LAST NEEDS_NO_SIZE TRUE
J 0
(-1350 3700);
DISPLAY 0.723404 (-1350 3700);
PAINT GREEN (-1350 3700);
DISPLAY INVISIBLE (-1350 3700);
FORCEPROP 2 LAST CDS_LIB pure_quanta
J 0
(-1350 3700);
DISPLAY INVISIBLE (-1350 3700);
FORCEADD OFFPAGE..5
(-8100 3200);
FORCEPROP 2 LAST $XR0 13 
J 0
(-8324 3200);
DISPLAY 0.638298 (-8324 3200);
PAINT MONO (-8324 3200);
FORCEPROP 2 LAST PATH I353
J 0
(-8050 3275);
DISPLAY 1.021277 (-8050 3275);
DISPLAY INVISIBLE (-8050 3275);
FORCEPROP 1 LAST COMMENT_BODY TRUE
J 0
(-8000 3125);
DISPLAY 0.872340 (-8000 3125);
PAINT GREEN (-8000 3125);
DISPLAY INVISIBLE (-8000 3125);
FORCEPROP 1 LAST OFFPAGE TRUE
J 0
(-7775 3075);
DISPLAY 0.872340 (-7775 3075);
PAINT GREEN (-7775 3075);
DISPLAY INVISIBLE (-7775 3075);
FORCEPROP 2 LAST CDS_LIB mstr_standard
J 0
(-8100 3200);
DISPLAY INVISIBLE (-8100 3200);
FORCEADD OFFPAGE..6
(-8375 3000);
FORCEPROP 2 LAST $XR5 136 
J 0
(-9134 3000);
DISPLAY 0.638298 (-9134 3000);
PAINT MONO (-9134 3000);
FORCEPROP 2 LAST $XR4 90 
J 0
(-9014 3000);
DISPLAY 0.638298 (-9014 3000);
PAINT MONO (-9014 3000);
FORCEPROP 2 LAST $XR3 89 
J 0
(-8924 3000);
DISPLAY 0.638298 (-8924 3000);
PAINT MONO (-8924 3000);
FORCEPROP 2 LAST $XR2 87 
J 0
(-8834 3000);
DISPLAY 0.638298 (-8834 3000);
PAINT MONO (-8834 3000);
FORCEPROP 2 LAST $XR1 86 
J 0
(-8744 3000);
DISPLAY 0.638298 (-8744 3000);
PAINT MONO (-8744 3000);
FORCEPROP 2 LAST $XR0 85 
J 0
(-8654 3000);
DISPLAY 0.638298 (-8654 3000);
PAINT MONO (-8654 3000);
FORCEPROP 2 LAST PATH I355
J 0
(-8650 3050);
DISPLAY 1.021277 (-8650 3050);
DISPLAY INVISIBLE (-8650 3050);
FORCEPROP 1 LAST COMMENT_BODY TRUE
J 0
(-8275 2925);
DISPLAY 0.872340 (-8275 2925);
PAINT GREEN (-8275 2925);
DISPLAY INVISIBLE (-8275 2925);
FORCEPROP 1 LAST OFFPAGE TRUE
J 0
(-8050 2875);
DISPLAY 0.872340 (-8050 2875);
PAINT GREEN (-8050 2875);
DISPLAY INVISIBLE (-8050 2875);
FORCEPROP 2 LAST CDS_LIB mstr_standard
J 0
(-8375 3000);
DISPLAY 0.808511 (-8375 3000);
DISPLAY INVISIBLE (-8375 3000);
FORCEADD GND..1
(-8600 3150);
FORCEPROP 3 LASTPIN (-8600 3200) SIG_NAME GND\g
J 0
(-8590 3210);
DISPLAY 0.659574 (-8590 3210);
PAINT MONO (-8590 3210);
DISPLAY INVISIBLE (-8590 3210);
FORCEPROP 2 LAST BOM_COST MEM
J 0
(-8575 3275);
DISPLAY 0.659574 (-8575 3275);
DISPLAY INVISIBLE (-8575 3275);
FORCEPROP 1 LAST SIZE 1B
J 0
(-8525 3100);
DISPLAY 0.723404 (-8525 3100);
PAINT GREEN (-8525 3100);
DISPLAY INVISIBLE (-8525 3100);
FORCEPROP 2 LAST CDS_LIB mstr_symbols
J 0
(-8600 3150);
DISPLAY 0.808511 (-8600 3150);
DISPLAY INVISIBLE (-8600 3150);
FORCEPROP 1 LAST BODY_TYPE PLUMBING
J 0
(-8645 3107);
DISPLAY 0.276596 (-8645 3107);
PAINT GREEN (-8645 3107);
DISPLAY INVISIBLE (-8645 3107);
FORCEPROP 1 LAST PATH I361
J 0
(-8525 3150);
DISPLAY 0.872340 (-8525 3150);
PAINT AQUA (-8525 3150);
DISPLAY INVISIBLE (-8525 3150);
FORCEPROP 1 LAST VOLTAGE 0
J 0
(-8620 3245);
DISPLAY 0.829787 (-8620 3245);
PAINT SKYBLUE (-8620 3245);
DISPLAY INVISIBLE (-8620 3245);
FORCEPROP 2 LAST ROOM MEM_EFGH_DECOUPLING_CAPS
J 0
(-8575 3225);
DISPLAY 0.659574 (-8575 3225);
PAINT RED (-8575 3225);
DISPLAY INVISIBLE (-8575 3225);
FORCEPROP 1 LAST HDL_POWER GND
J 0
(-8600 3300);
DISPLAY 0.723404 (-8600 3300);
PAINT GREEN (-8600 3300);
DISPLAY INVISIBLE (-8600 3300);
FORCEADD Q_CAP..1
R 2
(-8600 3375);
FORCEPROP 1 LAST LOCATION C100
J 2
(-8650 3475);
DISPLAY 0.489362 (-8650 3475);
PAINT SKYBLUE (-8650 3475);
FORCEPROP 0 LAST $SEC 1
J 0
(-8650 3525);
DISPLAY 0.680851 (-8650 3525);
PAINT MONO (-8650 3525);
DISPLAY INVISIBLE (-8650 3525);
FORCEPROP 0 LAST CDS_SEC 1
J 0
(-8650 3525);
DISPLAY 1.021277 (-8650 3525);
DISPLAY INVISIBLE (-8650 3525);
FORCEPROP 1 LASTPIN (-8600 3475) $PN 1
J 2
(-8610 3455);
DISPLAY 0.489362 (-8610 3455);
PAINT MONO (-8610 3455);
FORCEPROP 1 LASTPIN (-8600 3275) $PN 2
J 2
(-8610 3255);
DISPLAY 0.489362 (-8610 3255);
PAINT MONO (-8610 3255);
FORCEPROP 1 LAST MATERIAL X7R
J 2
(-8650 3275);
DISPLAY 0.489362 (-8650 3275);
PAINT SKYBLUE (-8650 3275);
FORCEPROP 1 LAST TOLERANCE 10%
J 2
(-8650 3325);
DISPLAY 0.489362 (-8650 3325);
PAINT SKYBLUE (-8650 3325);
FORCEPROP 1 LAST VALUE 0.1UF
J 2
(-8650 3425);
DISPLAY 0.489362 (-8650 3425);
PAINT SKYBLUE (-8650 3425);
FORCEPROP 1 LAST VOLTAGE 25V
J 2
(-8650 3375);
DISPLAY 0.489362 (-8650 3375);
PAINT SKYBLUE (-8650 3375);
FORCEPROP 1 LAST PART_NUMBER CH4104K1B00
J 2
(-8650 3225);
DISPLAY 0.489362 (-8650 3225);
PAINT SKYBLUE (-8650 3225);
FORCEPROP 1 LAST PACK_TYPE 0402
J 2
(-8650 3175);
DISPLAY 0.489362 (-8650 3175);
PAINT SKYBLUE (-8650 3175);
FORCEPROP 0 LAST BOM_COST MEM
J 2
(-8655 3520);
DISPLAY 0.595745 (-8655 3520);
PAINT MONO (-8655 3520);
DISPLAY INVISIBLE (-8655 3520);
FORCEPROP 2 LAST CDS_LIB pure_quanta
J 0
(-8600 3375);
DISPLAY INVISIBLE (-8600 3375);
FORCEPROP 1 LAST PATH I362
J 2
(-8650 3525);
DISPLAY 0.978723 (-8650 3525);
PAINT WHITE (-8650 3525);
DISPLAY INVISIBLE (-8650 3525);
FORCEPROP 0 LAST ROOM MEM_CH_A_CPU0_DIMM1
J 2
(-8655 3520);
DISPLAY 0.595745 (-8655 3520);
PAINT RED (-8655 3520);
DISPLAY INVISIBLE (-8655 3520);
FORCEADD Q_RES..2
(-8375 2450);
FORCEPROP 1 LAST LOCATION R92
J 0
(-8330 2575);
DISPLAY 0.489362 (-8330 2575);
PAINT SKYBLUE (-8330 2575);
FORCEPROP 0 LAST $SEC 1
J 0
(-8325 2625);
DISPLAY 0.680851 (-8325 2625);
PAINT MONO (-8325 2625);
DISPLAY INVISIBLE (-8325 2625);
FORCEPROP 0 LAST CDS_SEC 1
J 0
(-8325 2625);
DISPLAY 1.021277 (-8325 2625);
DISPLAY INVISIBLE (-8325 2625);
FORCEPROP 1 LASTPIN (-8375 2550) $PN 1
J 0
(-8370 2512);
DISPLAY 0.489362 (-8370 2512);
PAINT MONO (-8370 2512);
FORCEPROP 1 LASTPIN (-8375 2350) $PN 2
J 0
(-8370 2360);
DISPLAY 0.489362 (-8370 2360);
PAINT MONO (-8370 2360);
FORCEPROP 1 LAST WATTAGE 1/16W
J 0
(-8325 2475);
DISPLAY 0.489362 (-8325 2475);
PAINT SKYBLUE (-8325 2475);
FORCEPROP 1 LAST MATERIAL EMPTY
J 0
(-8325 2450);
DISPLAY 0.489362 (-8325 2450);
PAINT RED (-8325 2450);
FORCEPROP 1 LAST TOLERANCE 5%
J 0
(-8325 2500);
DISPLAY 0.489362 (-8325 2500);
PAINT SKYBLUE (-8325 2500);
FORCEPROP 1 LAST VALUE 1K
J 0
(-8330 2525);
DISPLAY 0.489362 (-8330 2525);
PAINT SKYBLUE (-8330 2525);
FORCEPROP 1 LAST PACK_TYPE 0402LF
J 0
(-8325 2400);
DISPLAY 0.489362 (-8325 2400);
PAINT SKYBLUE (-8325 2400);
FORCEPROP 2 LAST BOM_COST MEM
J 0
(-8325 2625);
DISPLAY 0.808511 (-8325 2625);
DISPLAY INVISIBLE (-8325 2625);
FORCEPROP 2 LAST CDS_LIB pure_quanta
J 0
(-8375 2450);
DISPLAY INVISIBLE (-8375 2450);
FORCEPROP 1 LAST PATH I367
J 0
(-8325 2625);
DISPLAY 0.978723 (-8325 2625);
PAINT WHITE (-8325 2625);
DISPLAY INVISIBLE (-8325 2625);
FORCEPROP 1 LAST PART_NUMBER TMP_QCS21002JB34
J 0
(-8325 2425);
DISPLAY 0.489362 (-8325 2425);
PAINT SKYBLUE (-8325 2425);
DISPLAY INVISIBLE (-8325 2425);
FORCEPROP 2 LAST ROOM MEM_CH_A_CPU0_DIMM1
J 0
(-8325 2675);
DISPLAY 0.808511 (-8325 2675);
PAINT RED (-8325 2675);
DISPLAY INVISIBLE (-8325 2675);
FORCEADD VCC_CORE..1
(-8375 2625);
FORCEPROP 3 LASTPIN (-8375 2575) SIG_NAME P3V3_STBY\g
J 0
(-8365 2585);
DISPLAY 0.659574 (-8365 2585);
PAINT MONO (-8365 2585);
DISPLAY INVISIBLE (-8365 2585);
FORCEPROP 1 LAST HDL_POWER P3V3_STBY
J 1
(-8375 2675);
DISPLAY 0.489362 (-8375 2675);
PAINT GREEN (-8375 2675);
FORCEPROP 2 LAST CDS_LIB mstr_symbols
J 0
(-8375 2625);
DISPLAY INVISIBLE (-8375 2625);
FORCEPROP 1 LAST PATH I368
J 0
(-8325 2650);
DISPLAY 0.872340 (-8325 2650);
PAINT AQUA (-8325 2650);
DISPLAY INVISIBLE (-8325 2650);
FORCEPROP 0 LAST VOLTAGE 3.3
J 0
(-8650 2775);
DISPLAY 1.021277 (-8650 2775);
PAINT SKYBLUE (-8650 2775);
DISPLAY INVISIBLE (-8650 2775);
FORCEPROP 2 LAST ROOM PVCCINFAON_CPU0_CTRL
J 0
(-8375 2725);
DISPLAY 0.808511 (-8375 2725);
PAINT RED (-8375 2725);
DISPLAY INVISIBLE (-8375 2725);
FORCEADD Q_RES..1
R 2
(-8500 2300);
FORCEPROP 1 LAST LOCATION R294
J 2
(-8450 2350);
DISPLAY 0.489362 (-8450 2350);
PAINT SKYBLUE (-8450 2350);
FORCEPROP 0 LAST $SEC 1
J 0
(-8450 2400);
DISPLAY 0.680851 (-8450 2400);
PAINT MONO (-8450 2400);
DISPLAY INVISIBLE (-8450 2400);
FORCEPROP 0 LAST CDS_SEC 1
J 0
(-8450 2400);
DISPLAY 1.021277 (-8450 2400);
DISPLAY INVISIBLE (-8450 2400);
FORCEPROP 1 LASTPIN (-8400 2300) $PN 1
J 2
(-8412 2312);
DISPLAY 0.489362 (-8412 2312);
PAINT MONO (-8412 2312);
FORCEPROP 1 LASTPIN (-8600 2300) $PN 2
J 2
(-8562 2312);
DISPLAY 0.489362 (-8562 2312);
PAINT MONO (-8562 2312);
FORCEPROP 1 LAST VALUE 0
J 0
(-8500 2250);
DISPLAY 0.489362 (-8500 2250);
PAINT SKYBLUE (-8500 2250);
FORCEPROP 2 LAST BOM_COST MEM
J 0
(-8525 2450);
DISPLAY 0.744681 (-8525 2450);
PAINT WHITE (-8525 2450);
DISPLAY INVISIBLE (-8525 2450);
FORCEPROP 2 LAST CDS_LIB pure_quanta
J 0
(-8500 2300);
DISPLAY INVISIBLE (-8500 2300);
FORCEPROP 1 LAST PATH I369
J 2
(-8450 2450);
DISPLAY 0.978723 (-8450 2450);
PAINT WHITE (-8450 2450);
DISPLAY INVISIBLE (-8450 2450);
FORCEPROP 1 LAST WATTAGE 1/16W
J 0
(-8425 2225);
DISPLAY 0.489362 (-8425 2225);
PAINT SKYBLUE (-8425 2225);
DISPLAY INVISIBLE (-8425 2225);
FORCEPROP 1 LAST MATERIAL CHIP
J 0
(-8675 2275);
DISPLAY 0.489362 (-8675 2275);
PAINT SKYBLUE (-8675 2275);
DISPLAY INVISIBLE (-8675 2275);
FORCEPROP 1 LAST TOLERANCE 5%
J 2
(-8375 2275);
DISPLAY 0.489362 (-8375 2275);
PAINT SKYBLUE (-8375 2275);
DISPLAY INVISIBLE (-8375 2275);
FORCEPROP 1 LAST PART_NUMBER CS00002JB38
J 0
(-8600 2350);
DISPLAY 0.489362 (-8600 2350);
PAINT SKYBLUE (-8600 2350);
DISPLAY INVISIBLE (-8600 2350);
FORCEPROP 1 LAST PACK_TYPE 0402LF
J 0
(-8675 2225);
DISPLAY 0.489362 (-8675 2225);
PAINT SKYBLUE (-8675 2225);
DISPLAY INVISIBLE (-8675 2225);
FORCEPROP 2 LAST ROOM RST_CPU0_PLD_TO_DIMM
J 0
(-8525 2400);
DISPLAY 0.744681 (-8525 2400);
PAINT RED (-8525 2400);
DISPLAY INVISIBLE (-8525 2400);
FORCEADD OFFPAGE..6
(-9000 2300);
FORCEPROP 2 LAST $XR5 81 
J 0
(-9429 2264);
DISPLAY 0.638298 (-9429 2264);
PAINT MONO (-9429 2264);
FORCEPROP 2 LAST $XR4 90 
J 0
(-9339 2264);
DISPLAY 0.638298 (-9339 2264);
PAINT MONO (-9339 2264);
FORCEPROP 2 LAST $XR3 89 
J 0
(-9249 2264);
DISPLAY 0.638298 (-9249 2264);
PAINT MONO (-9249 2264);
FORCEPROP 2 LAST $XR2 87 
J 0
(-9429 2300);
DISPLAY 0.638298 (-9429 2300);
PAINT MONO (-9429 2300);
FORCEPROP 2 LAST $XR1 86 
J 0
(-9339 2300);
DISPLAY 0.638298 (-9339 2300);
PAINT MONO (-9339 2300);
FORCEPROP 2 LAST $XR0 85 
J 0
(-9249 2300);
DISPLAY 0.638298 (-9249 2300);
PAINT MONO (-9249 2300);
FORCEPROP 2 LAST PATH I370
J 0
(-8950 2375);
DISPLAY 1.021277 (-8950 2375);
DISPLAY INVISIBLE (-8950 2375);
FORCEPROP 1 LAST COMMENT_BODY TRUE
J 0
(-8900 2225);
DISPLAY 0.872340 (-8900 2225);
PAINT GREEN (-8900 2225);
DISPLAY INVISIBLE (-8900 2225);
FORCEPROP 1 LAST OFFPAGE TRUE
J 0
(-8675 2175);
DISPLAY 0.872340 (-8675 2175);
PAINT GREEN (-8675 2175);
DISPLAY INVISIBLE (-8675 2175);
FORCEPROP 2 LAST CDS_LIB mstr_standard
J 0
(-9000 2300);
DISPLAY INVISIBLE (-9000 2300);
FORCEADD OFFPAGE..2
(-2700 3575);
FORCEPROP 2 LAST $XR0 13 
J 0
(-2511 3575);
DISPLAY 0.638298 (-2511 3575);
PAINT MONO (-2511 3575);
FORCEPROP 2 LAST PATH I371
J 0
(-2500 3625);
DISPLAY 0.680851 (-2500 3625);
DISPLAY INVISIBLE (-2500 3625);
FORCEPROP 1 LAST COMMENT_BODY TRUE
J 0
(-2745 3480);
DISPLAY 0.872340 (-2745 3480);
PAINT GREEN (-2745 3480);
DISPLAY INVISIBLE (-2745 3480);
FORCEPROP 1 LAST OFFPAGE TRUE
J 0
(-2375 3450);
DISPLAY 0.723404 (-2375 3450);
PAINT GREEN (-2375 3450);
DISPLAY INVISIBLE (-2375 3450);
FORCEPROP 2 LAST CDS_LIB mstr_standard
J 0
(-2700 3575);
DISPLAY 0.723404 (-2700 3575);
PAINT MONO (-2700 3575);
DISPLAY INVISIBLE (-2700 3575);
FORCEADD OFFPAGE..2
(-2700 3625);
FORCEPROP 2 LAST $XR0 13 
J 0
(-2511 3625);
DISPLAY 0.638298 (-2511 3625);
PAINT MONO (-2511 3625);
FORCEPROP 2 LAST PATH I372
J 0
(-2500 3675);
DISPLAY 0.680851 (-2500 3675);
DISPLAY INVISIBLE (-2500 3675);
FORCEPROP 1 LAST COMMENT_BODY TRUE
J 0
(-2745 3530);
DISPLAY 0.872340 (-2745 3530);
PAINT GREEN (-2745 3530);
DISPLAY INVISIBLE (-2745 3530);
FORCEPROP 1 LAST OFFPAGE TRUE
J 0
(-2375 3500);
DISPLAY 0.723404 (-2375 3500);
PAINT GREEN (-2375 3500);
DISPLAY INVISIBLE (-2375 3500);
FORCEPROP 2 LAST CDS_LIB mstr_standard
J 0
(-2700 3625);
DISPLAY 0.723404 (-2700 3625);
PAINT MONO (-2700 3625);
DISPLAY INVISIBLE (-2700 3625);
FORCEADD OFFPAGE..2
(-2700 4625);
FORCEPROP 2 LAST $XR0 13 
J 0
(-2511 4625);
DISPLAY 0.638298 (-2511 4625);
PAINT MONO (-2511 4625);
FORCEPROP 2 LAST PATH I373
J 0
(-2500 4675);
DISPLAY 0.680851 (-2500 4675);
DISPLAY INVISIBLE (-2500 4675);
FORCEPROP 1 LAST COMMENT_BODY TRUE
J 0
(-2745 4530);
DISPLAY 0.872340 (-2745 4530);
PAINT GREEN (-2745 4530);
DISPLAY INVISIBLE (-2745 4530);
FORCEPROP 1 LAST OFFPAGE TRUE
J 0
(-2375 4500);
DISPLAY 0.723404 (-2375 4500);
PAINT GREEN (-2375 4500);
DISPLAY INVISIBLE (-2375 4500);
FORCEPROP 2 LAST CDS_LIB mstr_standard
J 0
(-2700 4625);
DISPLAY 0.723404 (-2700 4625);
PAINT MONO (-2700 4625);
DISPLAY INVISIBLE (-2700 4625);
FORCEADD OFFPAGE..2
(-2700 4675);
FORCEPROP 2 LAST $XR0 13 
J 0
(-2511 4675);
DISPLAY 0.638298 (-2511 4675);
PAINT MONO (-2511 4675);
FORCEPROP 2 LAST PATH I374
J 0
(-2500 4725);
DISPLAY 0.680851 (-2500 4725);
DISPLAY INVISIBLE (-2500 4725);
FORCEPROP 1 LAST COMMENT_BODY TRUE
J 0
(-2745 4580);
DISPLAY 0.872340 (-2745 4580);
PAINT GREEN (-2745 4580);
DISPLAY INVISIBLE (-2745 4580);
FORCEPROP 1 LAST OFFPAGE TRUE
J 0
(-2375 4550);
DISPLAY 0.723404 (-2375 4550);
PAINT GREEN (-2375 4550);
DISPLAY INVISIBLE (-2375 4550);
FORCEPROP 2 LAST CDS_LIB mstr_standard
J 0
(-2700 4675);
DISPLAY 0.723404 (-2700 4675);
PAINT MONO (-2700 4675);
DISPLAY INVISIBLE (-2700 4675);
FORCEADD TAP..1
(-3500 4575);
FORCEPROP 3 LASTPIN (-3550 4575) SIG_NAME M_D_CPU0_SA_DQS_DN<9>
J 0
(-3540 4585);
DISPLAY 0.659574 (-3540 4585);
PAINT MONO (-3540 4585);
DISPLAY INVISIBLE (-3540 4585);
FORCEPROP 1 LASTPIN (-3550 4575) BN 9
J 0
(-3562 4583);
DISPLAY 0.489362 (-3562 4583);
PAINT GREEN (-3562 4583);
FORCEPROP 2 LAST CDS_LIB mstr_standard
J 0
(-3500 4575);
DISPLAY 0.723404 (-3500 4575);
PAINT MONO (-3500 4575);
DISPLAY INVISIBLE (-3500 4575);
FORCEPROP 1 LAST BODY_TYPE PLUMBING
J 0
(-3500 4625);
DISPLAY 0.872340 (-3500 4625);
PAINT GREEN (-3500 4625);
DISPLAY INVISIBLE (-3500 4625);
FORCEPROP 1 LAST HDL_TAP TRUE
J 0
(-3175 4450);
DISPLAY 0.872340 (-3175 4450);
DISPLAY INVISIBLE (-3175 4450);
FORCEPROP 1 LAST PATH I375
J 0
(-3502 4575);
DISPLAY 0.872340 (-3502 4575);
PAINT GREEN (-3502 4575);
DISPLAY INVISIBLE (-3502 4575);
FORCEADD TAP..1
(-3500 4475);
FORCEPROP 3 LASTPIN (-3550 4475) SIG_NAME M_D_CPU0_SA_DQS_DN<8>
J 0
(-3540 4485);
DISPLAY 0.659574 (-3540 4485);
PAINT MONO (-3540 4485);
DISPLAY INVISIBLE (-3540 4485);
FORCEPROP 1 LASTPIN (-3550 4475) BN 8
J 0
(-3562 4483);
DISPLAY 0.489362 (-3562 4483);
PAINT GREEN (-3562 4483);
FORCEPROP 2 LAST CDS_LIB mstr_standard
J 0
(-3500 4475);
DISPLAY 0.723404 (-3500 4475);
PAINT MONO (-3500 4475);
DISPLAY INVISIBLE (-3500 4475);
FORCEPROP 1 LAST BODY_TYPE PLUMBING
J 0
(-3500 4525);
DISPLAY 0.872340 (-3500 4525);
PAINT GREEN (-3500 4525);
DISPLAY INVISIBLE (-3500 4525);
FORCEPROP 1 LAST HDL_TAP TRUE
J 0
(-3175 4350);
DISPLAY 0.872340 (-3175 4350);
DISPLAY INVISIBLE (-3175 4350);
FORCEPROP 1 LAST PATH I376
J 0
(-3502 4475);
DISPLAY 0.872340 (-3502 4475);
PAINT GREEN (-3502 4475);
DISPLAY INVISIBLE (-3502 4475);
FORCEADD TAP..1
(-3500 4375);
FORCEPROP 3 LASTPIN (-3550 4375) SIG_NAME M_D_CPU0_SA_DQS_DN<7>
J 0
(-3540 4385);
DISPLAY 0.659574 (-3540 4385);
PAINT MONO (-3540 4385);
DISPLAY INVISIBLE (-3540 4385);
FORCEPROP 1 LASTPIN (-3550 4375) BN 7
J 0
(-3562 4383);
DISPLAY 0.489362 (-3562 4383);
PAINT GREEN (-3562 4383);
FORCEPROP 2 LAST CDS_LIB mstr_standard
J 0
(-3500 4375);
DISPLAY 0.723404 (-3500 4375);
PAINT MONO (-3500 4375);
DISPLAY INVISIBLE (-3500 4375);
FORCEPROP 1 LAST BODY_TYPE PLUMBING
J 0
(-3500 4425);
DISPLAY 0.872340 (-3500 4425);
PAINT GREEN (-3500 4425);
DISPLAY INVISIBLE (-3500 4425);
FORCEPROP 1 LAST HDL_TAP TRUE
J 0
(-3175 4250);
DISPLAY 0.872340 (-3175 4250);
DISPLAY INVISIBLE (-3175 4250);
FORCEPROP 1 LAST PATH I377
J 0
(-3502 4375);
DISPLAY 0.872340 (-3502 4375);
PAINT GREEN (-3502 4375);
DISPLAY INVISIBLE (-3502 4375);
FORCEADD TAP..1
(-3500 4275);
FORCEPROP 3 LASTPIN (-3550 4275) SIG_NAME M_D_CPU0_SA_DQS_DN<6>
J 0
(-3540 4285);
DISPLAY 0.659574 (-3540 4285);
PAINT MONO (-3540 4285);
DISPLAY INVISIBLE (-3540 4285);
FORCEPROP 1 LASTPIN (-3550 4275) BN 6
J 0
(-3562 4283);
DISPLAY 0.489362 (-3562 4283);
PAINT GREEN (-3562 4283);
FORCEPROP 2 LAST CDS_LIB mstr_standard
J 0
(-3500 4275);
DISPLAY 0.723404 (-3500 4275);
PAINT MONO (-3500 4275);
DISPLAY INVISIBLE (-3500 4275);
FORCEPROP 1 LAST BODY_TYPE PLUMBING
J 0
(-3500 4325);
DISPLAY 0.872340 (-3500 4325);
PAINT GREEN (-3500 4325);
DISPLAY INVISIBLE (-3500 4325);
FORCEPROP 1 LAST HDL_TAP TRUE
J 0
(-3175 4150);
DISPLAY 0.872340 (-3175 4150);
DISPLAY INVISIBLE (-3175 4150);
FORCEPROP 1 LAST PATH I378
J 0
(-3502 4275);
DISPLAY 0.872340 (-3502 4275);
PAINT GREEN (-3502 4275);
DISPLAY INVISIBLE (-3502 4275);
FORCEADD TAP..1
(-3700 4525);
FORCEPROP 3 LASTPIN (-3750 4525) SIG_NAME M_D_CPU0_SA_DQS_DP<8>
J 0
(-3740 4535);
DISPLAY 0.659574 (-3740 4535);
PAINT MONO (-3740 4535);
DISPLAY INVISIBLE (-3740 4535);
FORCEPROP 1 LASTPIN (-3750 4525) BN 8
J 0
(-3762 4533);
DISPLAY 0.489362 (-3762 4533);
PAINT GREEN (-3762 4533);
FORCEPROP 2 LAST CDS_LIB mstr_standard
J 0
(-3700 4525);
DISPLAY 0.723404 (-3700 4525);
PAINT MONO (-3700 4525);
DISPLAY INVISIBLE (-3700 4525);
FORCEPROP 1 LAST BODY_TYPE PLUMBING
J 0
(-3700 4575);
DISPLAY 0.872340 (-3700 4575);
PAINT GREEN (-3700 4575);
DISPLAY INVISIBLE (-3700 4575);
FORCEPROP 1 LAST HDL_TAP TRUE
J 0
(-3375 4400);
DISPLAY 0.872340 (-3375 4400);
DISPLAY INVISIBLE (-3375 4400);
FORCEPROP 1 LAST PATH I379
J 0
(-3702 4525);
DISPLAY 0.872340 (-3702 4525);
PAINT GREEN (-3702 4525);
DISPLAY INVISIBLE (-3702 4525);
FORCEADD TAP..1
(-3700 4625);
FORCEPROP 3 LASTPIN (-3750 4625) SIG_NAME M_D_CPU0_SA_DQS_DP<9>
J 0
(-3740 4635);
DISPLAY 0.659574 (-3740 4635);
PAINT MONO (-3740 4635);
DISPLAY INVISIBLE (-3740 4635);
FORCEPROP 1 LASTPIN (-3750 4625) BN 9
J 0
(-3762 4633);
DISPLAY 0.489362 (-3762 4633);
PAINT GREEN (-3762 4633);
FORCEPROP 2 LAST CDS_LIB mstr_standard
J 0
(-3700 4625);
DISPLAY 0.723404 (-3700 4625);
PAINT MONO (-3700 4625);
DISPLAY INVISIBLE (-3700 4625);
FORCEPROP 1 LAST BODY_TYPE PLUMBING
J 0
(-3700 4675);
DISPLAY 0.872340 (-3700 4675);
PAINT GREEN (-3700 4675);
DISPLAY INVISIBLE (-3700 4675);
FORCEPROP 1 LAST HDL_TAP TRUE
J 0
(-3375 4500);
DISPLAY 0.872340 (-3375 4500);
DISPLAY INVISIBLE (-3375 4500);
FORCEPROP 1 LAST PATH I380
J 0
(-3702 4625);
DISPLAY 0.872340 (-3702 4625);
PAINT GREEN (-3702 4625);
DISPLAY INVISIBLE (-3702 4625);
FORCEADD TAP..1
(-3700 4425);
FORCEPROP 3 LASTPIN (-3750 4425) SIG_NAME M_D_CPU0_SA_DQS_DP<7>
J 0
(-3740 4435);
DISPLAY 0.659574 (-3740 4435);
PAINT MONO (-3740 4435);
DISPLAY INVISIBLE (-3740 4435);
FORCEPROP 1 LASTPIN (-3750 4425) BN 7
J 0
(-3762 4433);
DISPLAY 0.489362 (-3762 4433);
PAINT GREEN (-3762 4433);
FORCEPROP 2 LAST CDS_LIB mstr_standard
J 0
(-3700 4425);
DISPLAY 0.723404 (-3700 4425);
PAINT MONO (-3700 4425);
DISPLAY INVISIBLE (-3700 4425);
FORCEPROP 1 LAST BODY_TYPE PLUMBING
J 0
(-3700 4475);
DISPLAY 0.872340 (-3700 4475);
PAINT GREEN (-3700 4475);
DISPLAY INVISIBLE (-3700 4475);
FORCEPROP 1 LAST HDL_TAP TRUE
J 0
(-3375 4300);
DISPLAY 0.872340 (-3375 4300);
DISPLAY INVISIBLE (-3375 4300);
FORCEPROP 1 LAST PATH I381
J 0
(-3702 4425);
DISPLAY 0.872340 (-3702 4425);
PAINT GREEN (-3702 4425);
DISPLAY INVISIBLE (-3702 4425);
FORCEADD TAP..1
(-3700 4325);
FORCEPROP 3 LASTPIN (-3750 4325) SIG_NAME M_D_CPU0_SA_DQS_DP<6>
J 0
(-3740 4335);
DISPLAY 0.659574 (-3740 4335);
PAINT MONO (-3740 4335);
DISPLAY INVISIBLE (-3740 4335);
FORCEPROP 1 LASTPIN (-3750 4325) BN 6
J 0
(-3762 4333);
DISPLAY 0.489362 (-3762 4333);
PAINT GREEN (-3762 4333);
FORCEPROP 2 LAST CDS_LIB mstr_standard
J 0
(-3700 4325);
DISPLAY 0.723404 (-3700 4325);
PAINT MONO (-3700 4325);
DISPLAY INVISIBLE (-3700 4325);
FORCEPROP 1 LAST BODY_TYPE PLUMBING
J 0
(-3700 4375);
DISPLAY 0.872340 (-3700 4375);
PAINT GREEN (-3700 4375);
DISPLAY INVISIBLE (-3700 4375);
FORCEPROP 1 LAST HDL_TAP TRUE
J 0
(-3375 4200);
DISPLAY 0.872340 (-3375 4200);
DISPLAY INVISIBLE (-3375 4200);
FORCEPROP 1 LAST PATH I382
J 0
(-3702 4325);
DISPLAY 0.872340 (-3702 4325);
PAINT GREEN (-3702 4325);
DISPLAY INVISIBLE (-3702 4325);
FORCEADD TAP..1
(-3500 4175);
FORCEPROP 3 LASTPIN (-3550 4175) SIG_NAME M_D_CPU0_SA_DQS_DN<5>
J 0
(-3540 4185);
DISPLAY 0.659574 (-3540 4185);
PAINT MONO (-3540 4185);
DISPLAY INVISIBLE (-3540 4185);
FORCEPROP 1 LASTPIN (-3550 4175) BN 5
J 0
(-3562 4183);
DISPLAY 0.489362 (-3562 4183);
PAINT GREEN (-3562 4183);
FORCEPROP 2 LAST CDS_LIB mstr_standard
J 0
(-3500 4175);
DISPLAY 0.723404 (-3500 4175);
PAINT MONO (-3500 4175);
DISPLAY INVISIBLE (-3500 4175);
FORCEPROP 1 LAST BODY_TYPE PLUMBING
J 0
(-3500 4225);
DISPLAY 0.872340 (-3500 4225);
PAINT GREEN (-3500 4225);
DISPLAY INVISIBLE (-3500 4225);
FORCEPROP 1 LAST HDL_TAP TRUE
J 0
(-3175 4050);
DISPLAY 0.872340 (-3175 4050);
DISPLAY INVISIBLE (-3175 4050);
FORCEPROP 1 LAST PATH I383
J 0
(-3502 4175);
DISPLAY 0.872340 (-3502 4175);
PAINT GREEN (-3502 4175);
DISPLAY INVISIBLE (-3502 4175);
FORCEADD TAP..1
(-3500 4075);
FORCEPROP 3 LASTPIN (-3550 4075) SIG_NAME M_D_CPU0_SA_DQS_DN<4>
J 0
(-3540 4085);
DISPLAY 0.659574 (-3540 4085);
PAINT MONO (-3540 4085);
DISPLAY INVISIBLE (-3540 4085);
FORCEPROP 1 LASTPIN (-3550 4075) BN 4
J 0
(-3562 4083);
DISPLAY 0.489362 (-3562 4083);
PAINT GREEN (-3562 4083);
FORCEPROP 2 LAST CDS_LIB mstr_standard
J 0
(-3500 4075);
DISPLAY 0.723404 (-3500 4075);
PAINT MONO (-3500 4075);
DISPLAY INVISIBLE (-3500 4075);
FORCEPROP 1 LAST BODY_TYPE PLUMBING
J 0
(-3500 4125);
DISPLAY 0.872340 (-3500 4125);
PAINT GREEN (-3500 4125);
DISPLAY INVISIBLE (-3500 4125);
FORCEPROP 1 LAST HDL_TAP TRUE
J 0
(-3175 3950);
DISPLAY 0.872340 (-3175 3950);
DISPLAY INVISIBLE (-3175 3950);
FORCEPROP 1 LAST PATH I384
J 0
(-3502 4075);
DISPLAY 0.872340 (-3502 4075);
PAINT GREEN (-3502 4075);
DISPLAY INVISIBLE (-3502 4075);
FORCEADD TAP..1
(-3500 3975);
FORCEPROP 3 LASTPIN (-3550 3975) SIG_NAME M_D_CPU0_SA_DQS_DN<3>
J 0
(-3540 3985);
DISPLAY 0.659574 (-3540 3985);
PAINT MONO (-3540 3985);
DISPLAY INVISIBLE (-3540 3985);
FORCEPROP 1 LASTPIN (-3550 3975) BN 3
J 0
(-3562 3983);
DISPLAY 0.489362 (-3562 3983);
PAINT GREEN (-3562 3983);
FORCEPROP 2 LAST CDS_LIB mstr_standard
J 0
(-3500 3975);
DISPLAY 0.723404 (-3500 3975);
PAINT MONO (-3500 3975);
DISPLAY INVISIBLE (-3500 3975);
FORCEPROP 1 LAST BODY_TYPE PLUMBING
J 0
(-3500 4025);
DISPLAY 0.872340 (-3500 4025);
PAINT GREEN (-3500 4025);
DISPLAY INVISIBLE (-3500 4025);
FORCEPROP 1 LAST HDL_TAP TRUE
J 0
(-3175 3850);
DISPLAY 0.872340 (-3175 3850);
DISPLAY INVISIBLE (-3175 3850);
FORCEPROP 1 LAST PATH I385
J 0
(-3502 3975);
DISPLAY 0.872340 (-3502 3975);
PAINT GREEN (-3502 3975);
DISPLAY INVISIBLE (-3502 3975);
FORCEADD TAP..1
(-3500 3875);
FORCEPROP 3 LASTPIN (-3550 3875) SIG_NAME M_D_CPU0_SA_DQS_DN<2>
J 0
(-3540 3885);
DISPLAY 0.659574 (-3540 3885);
PAINT MONO (-3540 3885);
DISPLAY INVISIBLE (-3540 3885);
FORCEPROP 1 LASTPIN (-3550 3875) BN 2
J 0
(-3562 3883);
DISPLAY 0.489362 (-3562 3883);
PAINT GREEN (-3562 3883);
FORCEPROP 2 LAST CDS_LIB mstr_standard
J 0
(-3500 3875);
DISPLAY 0.723404 (-3500 3875);
PAINT MONO (-3500 3875);
DISPLAY INVISIBLE (-3500 3875);
FORCEPROP 1 LAST BODY_TYPE PLUMBING
J 0
(-3500 3925);
DISPLAY 0.872340 (-3500 3925);
PAINT GREEN (-3500 3925);
DISPLAY INVISIBLE (-3500 3925);
FORCEPROP 1 LAST HDL_TAP TRUE
J 0
(-3175 3750);
DISPLAY 0.872340 (-3175 3750);
DISPLAY INVISIBLE (-3175 3750);
FORCEPROP 1 LAST PATH I386
J 0
(-3502 3875);
DISPLAY 0.872340 (-3502 3875);
PAINT GREEN (-3502 3875);
DISPLAY INVISIBLE (-3502 3875);
FORCEADD TAP..1
(-3500 3775);
FORCEPROP 3 LASTPIN (-3550 3775) SIG_NAME M_D_CPU0_SA_DQS_DN<1>
J 0
(-3540 3785);
DISPLAY 0.659574 (-3540 3785);
PAINT MONO (-3540 3785);
DISPLAY INVISIBLE (-3540 3785);
FORCEPROP 1 LASTPIN (-3550 3775) BN 1
J 0
(-3562 3783);
DISPLAY 0.489362 (-3562 3783);
PAINT GREEN (-3562 3783);
FORCEPROP 2 LAST CDS_LIB mstr_standard
J 0
(-3500 3775);
DISPLAY 0.723404 (-3500 3775);
PAINT MONO (-3500 3775);
DISPLAY INVISIBLE (-3500 3775);
FORCEPROP 1 LAST BODY_TYPE PLUMBING
J 0
(-3500 3825);
DISPLAY 0.872340 (-3500 3825);
PAINT GREEN (-3500 3825);
DISPLAY INVISIBLE (-3500 3825);
FORCEPROP 1 LAST HDL_TAP TRUE
J 0
(-3175 3650);
DISPLAY 0.872340 (-3175 3650);
DISPLAY INVISIBLE (-3175 3650);
FORCEPROP 1 LAST PATH I387
J 0
(-3502 3775);
DISPLAY 0.872340 (-3502 3775);
PAINT GREEN (-3502 3775);
DISPLAY INVISIBLE (-3502 3775);
FORCEADD TAP..1
(-3700 4225);
FORCEPROP 3 LASTPIN (-3750 4225) SIG_NAME M_D_CPU0_SA_DQS_DP<5>
J 0
(-3740 4235);
DISPLAY 0.659574 (-3740 4235);
PAINT MONO (-3740 4235);
DISPLAY INVISIBLE (-3740 4235);
FORCEPROP 1 LASTPIN (-3750 4225) BN 5
J 0
(-3762 4233);
DISPLAY 0.489362 (-3762 4233);
PAINT GREEN (-3762 4233);
FORCEPROP 2 LAST CDS_LIB mstr_standard
J 0
(-3700 4225);
DISPLAY 0.723404 (-3700 4225);
PAINT MONO (-3700 4225);
DISPLAY INVISIBLE (-3700 4225);
FORCEPROP 1 LAST BODY_TYPE PLUMBING
J 0
(-3700 4275);
DISPLAY 0.872340 (-3700 4275);
PAINT GREEN (-3700 4275);
DISPLAY INVISIBLE (-3700 4275);
FORCEPROP 1 LAST HDL_TAP TRUE
J 0
(-3375 4100);
DISPLAY 0.872340 (-3375 4100);
DISPLAY INVISIBLE (-3375 4100);
FORCEPROP 1 LAST PATH I388
J 0
(-3702 4225);
DISPLAY 0.872340 (-3702 4225);
PAINT GREEN (-3702 4225);
DISPLAY INVISIBLE (-3702 4225);
FORCEADD TAP..1
(-3700 4125);
FORCEPROP 3 LASTPIN (-3750 4125) SIG_NAME M_D_CPU0_SA_DQS_DP<4>
J 0
(-3740 4135);
DISPLAY 0.659574 (-3740 4135);
PAINT MONO (-3740 4135);
DISPLAY INVISIBLE (-3740 4135);
FORCEPROP 1 LASTPIN (-3750 4125) BN 4
J 0
(-3762 4133);
DISPLAY 0.489362 (-3762 4133);
PAINT GREEN (-3762 4133);
FORCEPROP 2 LAST CDS_LIB mstr_standard
J 0
(-3700 4125);
DISPLAY 0.723404 (-3700 4125);
PAINT MONO (-3700 4125);
DISPLAY INVISIBLE (-3700 4125);
FORCEPROP 1 LAST BODY_TYPE PLUMBING
J 0
(-3700 4175);
DISPLAY 0.872340 (-3700 4175);
PAINT GREEN (-3700 4175);
DISPLAY INVISIBLE (-3700 4175);
FORCEPROP 1 LAST HDL_TAP TRUE
J 0
(-3375 4000);
DISPLAY 0.872340 (-3375 4000);
DISPLAY INVISIBLE (-3375 4000);
FORCEPROP 1 LAST PATH I389
J 0
(-3702 4125);
DISPLAY 0.872340 (-3702 4125);
PAINT GREEN (-3702 4125);
DISPLAY INVISIBLE (-3702 4125);
FORCEADD TAP..1
(-3700 4025);
FORCEPROP 3 LASTPIN (-3750 4025) SIG_NAME M_D_CPU0_SA_DQS_DP<3>
J 0
(-3740 4035);
DISPLAY 0.659574 (-3740 4035);
PAINT MONO (-3740 4035);
DISPLAY INVISIBLE (-3740 4035);
FORCEPROP 1 LASTPIN (-3750 4025) BN 3
J 0
(-3762 4033);
DISPLAY 0.489362 (-3762 4033);
PAINT GREEN (-3762 4033);
FORCEPROP 2 LAST CDS_LIB mstr_standard
J 0
(-3700 4025);
DISPLAY 0.723404 (-3700 4025);
PAINT MONO (-3700 4025);
DISPLAY INVISIBLE (-3700 4025);
FORCEPROP 1 LAST BODY_TYPE PLUMBING
J 0
(-3700 4075);
DISPLAY 0.872340 (-3700 4075);
PAINT GREEN (-3700 4075);
DISPLAY INVISIBLE (-3700 4075);
FORCEPROP 1 LAST HDL_TAP TRUE
J 0
(-3375 3900);
DISPLAY 0.872340 (-3375 3900);
DISPLAY INVISIBLE (-3375 3900);
FORCEPROP 1 LAST PATH I390
J 0
(-3702 4025);
DISPLAY 0.872340 (-3702 4025);
PAINT GREEN (-3702 4025);
DISPLAY INVISIBLE (-3702 4025);
FORCEADD TAP..1
(-3700 3925);
FORCEPROP 3 LASTPIN (-3750 3925) SIG_NAME M_D_CPU0_SA_DQS_DP<2>
J 0
(-3740 3935);
DISPLAY 0.659574 (-3740 3935);
PAINT MONO (-3740 3935);
DISPLAY INVISIBLE (-3740 3935);
FORCEPROP 1 LASTPIN (-3750 3925) BN 2
J 0
(-3762 3933);
DISPLAY 0.489362 (-3762 3933);
PAINT GREEN (-3762 3933);
FORCEPROP 2 LAST CDS_LIB mstr_standard
J 0
(-3700 3925);
DISPLAY 0.723404 (-3700 3925);
PAINT MONO (-3700 3925);
DISPLAY INVISIBLE (-3700 3925);
FORCEPROP 1 LAST BODY_TYPE PLUMBING
J 0
(-3700 3975);
DISPLAY 0.872340 (-3700 3975);
PAINT GREEN (-3700 3975);
DISPLAY INVISIBLE (-3700 3975);
FORCEPROP 1 LAST HDL_TAP TRUE
J 0
(-3375 3800);
DISPLAY 0.872340 (-3375 3800);
DISPLAY INVISIBLE (-3375 3800);
FORCEPROP 1 LAST PATH I391
J 0
(-3702 3925);
DISPLAY 0.872340 (-3702 3925);
PAINT GREEN (-3702 3925);
DISPLAY INVISIBLE (-3702 3925);
FORCEADD TAP..1
(-3700 3825);
FORCEPROP 3 LASTPIN (-3750 3825) SIG_NAME M_D_CPU0_SA_DQS_DP<1>
J 0
(-3740 3835);
DISPLAY 0.659574 (-3740 3835);
PAINT MONO (-3740 3835);
DISPLAY INVISIBLE (-3740 3835);
FORCEPROP 1 LASTPIN (-3750 3825) BN 1
J 0
(-3762 3833);
DISPLAY 0.489362 (-3762 3833);
PAINT GREEN (-3762 3833);
FORCEPROP 2 LAST CDS_LIB mstr_standard
J 0
(-3700 3825);
DISPLAY 0.723404 (-3700 3825);
PAINT MONO (-3700 3825);
DISPLAY INVISIBLE (-3700 3825);
FORCEPROP 1 LAST BODY_TYPE PLUMBING
J 0
(-3700 3875);
DISPLAY 0.872340 (-3700 3875);
PAINT GREEN (-3700 3875);
DISPLAY INVISIBLE (-3700 3875);
FORCEPROP 1 LAST HDL_TAP TRUE
J 0
(-3375 3700);
DISPLAY 0.872340 (-3375 3700);
DISPLAY INVISIBLE (-3375 3700);
FORCEPROP 1 LAST PATH I392
J 0
(-3702 3825);
DISPLAY 0.872340 (-3702 3825);
PAINT GREEN (-3702 3825);
DISPLAY INVISIBLE (-3702 3825);
FORCEADD TAP..1
(-3500 3675);
FORCEPROP 3 LASTPIN (-3550 3675) SIG_NAME M_D_CPU0_SA_DQS_DN<0>
J 0
(-3540 3685);
DISPLAY 0.659574 (-3540 3685);
PAINT MONO (-3540 3685);
DISPLAY INVISIBLE (-3540 3685);
FORCEPROP 1 LASTPIN (-3550 3675) BN 0
J 0
(-3562 3683);
DISPLAY 0.489362 (-3562 3683);
PAINT GREEN (-3562 3683);
FORCEPROP 2 LAST CDS_LIB mstr_standard
J 0
(-3500 3675);
DISPLAY 0.723404 (-3500 3675);
PAINT MONO (-3500 3675);
DISPLAY INVISIBLE (-3500 3675);
FORCEPROP 1 LAST BODY_TYPE PLUMBING
J 0
(-3500 3725);
DISPLAY 0.872340 (-3500 3725);
PAINT GREEN (-3500 3725);
DISPLAY INVISIBLE (-3500 3725);
FORCEPROP 1 LAST HDL_TAP TRUE
J 0
(-3175 3550);
DISPLAY 0.872340 (-3175 3550);
DISPLAY INVISIBLE (-3175 3550);
FORCEPROP 1 LAST PATH I393
J 0
(-3502 3675);
DISPLAY 0.872340 (-3502 3675);
PAINT GREEN (-3502 3675);
DISPLAY INVISIBLE (-3502 3675);
FORCEADD TAP..1
(-3500 3525);
FORCEPROP 3 LASTPIN (-3550 3525) SIG_NAME M_D_CPU0_SB_DQS_DN<9>
J 0
(-3540 3535);
DISPLAY 0.659574 (-3540 3535);
PAINT MONO (-3540 3535);
DISPLAY INVISIBLE (-3540 3535);
FORCEPROP 1 LASTPIN (-3550 3525) BN 9
J 0
(-3562 3533);
DISPLAY 0.489362 (-3562 3533);
PAINT GREEN (-3562 3533);
FORCEPROP 2 LAST CDS_LIB mstr_standard
J 0
(-3500 3525);
DISPLAY 0.723404 (-3500 3525);
PAINT MONO (-3500 3525);
DISPLAY INVISIBLE (-3500 3525);
FORCEPROP 1 LAST BODY_TYPE PLUMBING
J 0
(-3500 3575);
DISPLAY 0.872340 (-3500 3575);
PAINT GREEN (-3500 3575);
DISPLAY INVISIBLE (-3500 3575);
FORCEPROP 1 LAST HDL_TAP TRUE
J 0
(-3175 3400);
DISPLAY 0.872340 (-3175 3400);
DISPLAY INVISIBLE (-3175 3400);
FORCEPROP 1 LAST PATH I394
J 0
(-3502 3525);
DISPLAY 0.872340 (-3502 3525);
PAINT GREEN (-3502 3525);
DISPLAY INVISIBLE (-3502 3525);
FORCEADD TAP..1
(-3500 3425);
FORCEPROP 3 LASTPIN (-3550 3425) SIG_NAME M_D_CPU0_SB_DQS_DN<8>
J 0
(-3540 3435);
DISPLAY 0.659574 (-3540 3435);
PAINT MONO (-3540 3435);
DISPLAY INVISIBLE (-3540 3435);
FORCEPROP 1 LASTPIN (-3550 3425) BN 8
J 0
(-3562 3433);
DISPLAY 0.489362 (-3562 3433);
PAINT GREEN (-3562 3433);
FORCEPROP 2 LAST CDS_LIB mstr_standard
J 0
(-3500 3425);
DISPLAY 0.723404 (-3500 3425);
PAINT MONO (-3500 3425);
DISPLAY INVISIBLE (-3500 3425);
FORCEPROP 1 LAST BODY_TYPE PLUMBING
J 0
(-3500 3475);
DISPLAY 0.872340 (-3500 3475);
PAINT GREEN (-3500 3475);
DISPLAY INVISIBLE (-3500 3475);
FORCEPROP 1 LAST HDL_TAP TRUE
J 0
(-3175 3300);
DISPLAY 0.872340 (-3175 3300);
DISPLAY INVISIBLE (-3175 3300);
FORCEPROP 1 LAST PATH I395
J 0
(-3502 3425);
DISPLAY 0.872340 (-3502 3425);
PAINT GREEN (-3502 3425);
DISPLAY INVISIBLE (-3502 3425);
FORCEADD TAP..1
(-3500 3325);
FORCEPROP 3 LASTPIN (-3550 3325) SIG_NAME M_D_CPU0_SB_DQS_DN<7>
J 0
(-3540 3335);
DISPLAY 0.659574 (-3540 3335);
PAINT MONO (-3540 3335);
DISPLAY INVISIBLE (-3540 3335);
FORCEPROP 1 LASTPIN (-3550 3325) BN 7
J 0
(-3562 3333);
DISPLAY 0.489362 (-3562 3333);
PAINT GREEN (-3562 3333);
FORCEPROP 2 LAST CDS_LIB mstr_standard
J 0
(-3500 3325);
DISPLAY 0.723404 (-3500 3325);
PAINT MONO (-3500 3325);
DISPLAY INVISIBLE (-3500 3325);
FORCEPROP 1 LAST BODY_TYPE PLUMBING
J 0
(-3500 3375);
DISPLAY 0.872340 (-3500 3375);
PAINT GREEN (-3500 3375);
DISPLAY INVISIBLE (-3500 3375);
FORCEPROP 1 LAST HDL_TAP TRUE
J 0
(-3175 3200);
DISPLAY 0.872340 (-3175 3200);
DISPLAY INVISIBLE (-3175 3200);
FORCEPROP 1 LAST PATH I396
J 0
(-3502 3325);
DISPLAY 0.872340 (-3502 3325);
PAINT GREEN (-3502 3325);
DISPLAY INVISIBLE (-3502 3325);
FORCEADD TAP..1
(-3700 3575);
FORCEPROP 3 LASTPIN (-3750 3575) SIG_NAME M_D_CPU0_SB_DQS_DP<9>
J 0
(-3740 3585);
DISPLAY 0.659574 (-3740 3585);
PAINT MONO (-3740 3585);
DISPLAY INVISIBLE (-3740 3585);
FORCEPROP 1 LASTPIN (-3750 3575) BN 9
J 0
(-3762 3583);
DISPLAY 0.489362 (-3762 3583);
PAINT GREEN (-3762 3583);
FORCEPROP 2 LAST CDS_LIB mstr_standard
J 0
(-3700 3575);
DISPLAY 0.723404 (-3700 3575);
PAINT MONO (-3700 3575);
DISPLAY INVISIBLE (-3700 3575);
FORCEPROP 1 LAST BODY_TYPE PLUMBING
J 0
(-3700 3625);
DISPLAY 0.872340 (-3700 3625);
PAINT GREEN (-3700 3625);
DISPLAY INVISIBLE (-3700 3625);
FORCEPROP 1 LAST HDL_TAP TRUE
J 0
(-3375 3450);
DISPLAY 0.872340 (-3375 3450);
DISPLAY INVISIBLE (-3375 3450);
FORCEPROP 1 LAST PATH I397
J 0
(-3702 3575);
DISPLAY 0.872340 (-3702 3575);
PAINT GREEN (-3702 3575);
DISPLAY INVISIBLE (-3702 3575);
FORCEADD TAP..1
(-3700 3725);
FORCEPROP 3 LASTPIN (-3750 3725) SIG_NAME M_D_CPU0_SA_DQS_DP<0>
J 0
(-3740 3735);
DISPLAY 0.659574 (-3740 3735);
PAINT MONO (-3740 3735);
DISPLAY INVISIBLE (-3740 3735);
FORCEPROP 1 LASTPIN (-3750 3725) BN 0
J 0
(-3762 3733);
DISPLAY 0.489362 (-3762 3733);
PAINT GREEN (-3762 3733);
FORCEPROP 2 LAST CDS_LIB mstr_standard
J 0
(-3700 3725);
DISPLAY 0.723404 (-3700 3725);
PAINT MONO (-3700 3725);
DISPLAY INVISIBLE (-3700 3725);
FORCEPROP 1 LAST BODY_TYPE PLUMBING
J 0
(-3700 3775);
DISPLAY 0.872340 (-3700 3775);
PAINT GREEN (-3700 3775);
DISPLAY INVISIBLE (-3700 3775);
FORCEPROP 1 LAST HDL_TAP TRUE
J 0
(-3375 3600);
DISPLAY 0.872340 (-3375 3600);
DISPLAY INVISIBLE (-3375 3600);
FORCEPROP 1 LAST PATH I398
J 0
(-3702 3725);
DISPLAY 0.872340 (-3702 3725);
PAINT GREEN (-3702 3725);
DISPLAY INVISIBLE (-3702 3725);
FORCEADD TAP..1
(-3700 3375);
FORCEPROP 3 LASTPIN (-3750 3375) SIG_NAME M_D_CPU0_SB_DQS_DP<7>
J 0
(-3740 3385);
DISPLAY 0.659574 (-3740 3385);
PAINT MONO (-3740 3385);
DISPLAY INVISIBLE (-3740 3385);
FORCEPROP 1 LASTPIN (-3750 3375) BN 7
J 0
(-3762 3383);
DISPLAY 0.489362 (-3762 3383);
PAINT GREEN (-3762 3383);
FORCEPROP 2 LAST CDS_LIB mstr_standard
J 0
(-3700 3375);
DISPLAY 0.723404 (-3700 3375);
PAINT MONO (-3700 3375);
DISPLAY INVISIBLE (-3700 3375);
FORCEPROP 1 LAST BODY_TYPE PLUMBING
J 0
(-3700 3425);
DISPLAY 0.872340 (-3700 3425);
PAINT GREEN (-3700 3425);
DISPLAY INVISIBLE (-3700 3425);
FORCEPROP 1 LAST HDL_TAP TRUE
J 0
(-3375 3250);
DISPLAY 0.872340 (-3375 3250);
DISPLAY INVISIBLE (-3375 3250);
FORCEPROP 1 LAST PATH I399
J 0
(-3702 3375);
DISPLAY 0.872340 (-3702 3375);
PAINT GREEN (-3702 3375);
DISPLAY INVISIBLE (-3702 3375);
FORCEADD TAP..1
(-3700 3475);
FORCEPROP 3 LASTPIN (-3750 3475) SIG_NAME M_D_CPU0_SB_DQS_DP<8>
J 0
(-3740 3485);
DISPLAY 0.659574 (-3740 3485);
PAINT MONO (-3740 3485);
DISPLAY INVISIBLE (-3740 3485);
FORCEPROP 1 LASTPIN (-3750 3475) BN 8
J 0
(-3762 3483);
DISPLAY 0.489362 (-3762 3483);
PAINT GREEN (-3762 3483);
FORCEPROP 2 LAST CDS_LIB mstr_standard
J 0
(-3700 3475);
DISPLAY 0.723404 (-3700 3475);
PAINT MONO (-3700 3475);
DISPLAY INVISIBLE (-3700 3475);
FORCEPROP 1 LAST BODY_TYPE PLUMBING
J 0
(-3700 3525);
DISPLAY 0.872340 (-3700 3525);
PAINT GREEN (-3700 3525);
DISPLAY INVISIBLE (-3700 3525);
FORCEPROP 1 LAST HDL_TAP TRUE
J 0
(-3375 3350);
DISPLAY 0.872340 (-3375 3350);
DISPLAY INVISIBLE (-3375 3350);
FORCEPROP 1 LAST PATH I400
J 0
(-3702 3475);
DISPLAY 0.872340 (-3702 3475);
PAINT GREEN (-3702 3475);
DISPLAY INVISIBLE (-3702 3475);
FORCEADD TAP..1
(-3700 3275);
FORCEPROP 3 LASTPIN (-3750 3275) SIG_NAME M_D_CPU0_SB_DQS_DP<6>
J 0
(-3740 3285);
DISPLAY 0.659574 (-3740 3285);
PAINT MONO (-3740 3285);
DISPLAY INVISIBLE (-3740 3285);
FORCEPROP 1 LASTPIN (-3750 3275) BN 6
J 0
(-3762 3283);
DISPLAY 0.489362 (-3762 3283);
PAINT GREEN (-3762 3283);
FORCEPROP 2 LAST CDS_LIB mstr_standard
J 0
(-3700 3275);
DISPLAY 0.723404 (-3700 3275);
PAINT MONO (-3700 3275);
DISPLAY INVISIBLE (-3700 3275);
FORCEPROP 1 LAST BODY_TYPE PLUMBING
J 0
(-3700 3325);
DISPLAY 0.872340 (-3700 3325);
PAINT GREEN (-3700 3325);
DISPLAY INVISIBLE (-3700 3325);
FORCEPROP 1 LAST HDL_TAP TRUE
J 0
(-3375 3150);
DISPLAY 0.872340 (-3375 3150);
DISPLAY INVISIBLE (-3375 3150);
FORCEPROP 1 LAST PATH I401
J 0
(-3702 3275);
DISPLAY 0.872340 (-3702 3275);
PAINT GREEN (-3702 3275);
DISPLAY INVISIBLE (-3702 3275);
FORCEADD TAP..1
(-3500 3225);
FORCEPROP 3 LASTPIN (-3550 3225) SIG_NAME M_D_CPU0_SB_DQS_DN<6>
J 0
(-3540 3235);
DISPLAY 0.659574 (-3540 3235);
PAINT MONO (-3540 3235);
DISPLAY INVISIBLE (-3540 3235);
FORCEPROP 1 LASTPIN (-3550 3225) BN 6
J 0
(-3562 3233);
DISPLAY 0.489362 (-3562 3233);
PAINT GREEN (-3562 3233);
FORCEPROP 2 LAST CDS_LIB mstr_standard
J 0
(-3500 3225);
DISPLAY 0.723404 (-3500 3225);
PAINT MONO (-3500 3225);
DISPLAY INVISIBLE (-3500 3225);
FORCEPROP 1 LAST BODY_TYPE PLUMBING
J 0
(-3500 3275);
DISPLAY 0.872340 (-3500 3275);
PAINT GREEN (-3500 3275);
DISPLAY INVISIBLE (-3500 3275);
FORCEPROP 1 LAST HDL_TAP TRUE
J 0
(-3175 3100);
DISPLAY 0.872340 (-3175 3100);
DISPLAY INVISIBLE (-3175 3100);
FORCEPROP 1 LAST PATH I402
J 0
(-3502 3225);
DISPLAY 0.872340 (-3502 3225);
PAINT GREEN (-3502 3225);
DISPLAY INVISIBLE (-3502 3225);
FORCEADD TAP..1
(-3500 3125);
FORCEPROP 3 LASTPIN (-3550 3125) SIG_NAME M_D_CPU0_SB_DQS_DN<5>
J 0
(-3540 3135);
DISPLAY 0.659574 (-3540 3135);
PAINT MONO (-3540 3135);
DISPLAY INVISIBLE (-3540 3135);
FORCEPROP 1 LASTPIN (-3550 3125) BN 5
J 0
(-3562 3133);
DISPLAY 0.489362 (-3562 3133);
PAINT GREEN (-3562 3133);
FORCEPROP 2 LAST CDS_LIB mstr_standard
J 0
(-3500 3125);
DISPLAY 0.723404 (-3500 3125);
PAINT MONO (-3500 3125);
DISPLAY INVISIBLE (-3500 3125);
FORCEPROP 1 LAST BODY_TYPE PLUMBING
J 0
(-3500 3175);
DISPLAY 0.872340 (-3500 3175);
PAINT GREEN (-3500 3175);
DISPLAY INVISIBLE (-3500 3175);
FORCEPROP 1 LAST HDL_TAP TRUE
J 0
(-3175 3000);
DISPLAY 0.872340 (-3175 3000);
DISPLAY INVISIBLE (-3175 3000);
FORCEPROP 1 LAST PATH I403
J 0
(-3502 3125);
DISPLAY 0.872340 (-3502 3125);
PAINT GREEN (-3502 3125);
DISPLAY INVISIBLE (-3502 3125);
FORCEADD TAP..1
(-3500 3025);
FORCEPROP 3 LASTPIN (-3550 3025) SIG_NAME M_D_CPU0_SB_DQS_DN<4>
J 0
(-3540 3035);
DISPLAY 0.659574 (-3540 3035);
PAINT MONO (-3540 3035);
DISPLAY INVISIBLE (-3540 3035);
FORCEPROP 1 LASTPIN (-3550 3025) BN 4
J 0
(-3562 3033);
DISPLAY 0.489362 (-3562 3033);
PAINT GREEN (-3562 3033);
FORCEPROP 2 LAST CDS_LIB mstr_standard
J 0
(-3500 3025);
DISPLAY 0.723404 (-3500 3025);
PAINT MONO (-3500 3025);
DISPLAY INVISIBLE (-3500 3025);
FORCEPROP 1 LAST BODY_TYPE PLUMBING
J 0
(-3500 3075);
DISPLAY 0.872340 (-3500 3075);
PAINT GREEN (-3500 3075);
DISPLAY INVISIBLE (-3500 3075);
FORCEPROP 1 LAST HDL_TAP TRUE
J 0
(-3175 2900);
DISPLAY 0.872340 (-3175 2900);
DISPLAY INVISIBLE (-3175 2900);
FORCEPROP 1 LAST PATH I404
J 0
(-3502 3025);
DISPLAY 0.872340 (-3502 3025);
PAINT GREEN (-3502 3025);
DISPLAY INVISIBLE (-3502 3025);
FORCEADD TAP..1
(-3500 2925);
FORCEPROP 3 LASTPIN (-3550 2925) SIG_NAME M_D_CPU0_SB_DQS_DN<3>
J 0
(-3540 2935);
DISPLAY 0.659574 (-3540 2935);
PAINT MONO (-3540 2935);
DISPLAY INVISIBLE (-3540 2935);
FORCEPROP 1 LASTPIN (-3550 2925) BN 3
J 0
(-3562 2933);
DISPLAY 0.489362 (-3562 2933);
PAINT GREEN (-3562 2933);
FORCEPROP 2 LAST CDS_LIB mstr_standard
J 0
(-3500 2925);
DISPLAY 0.723404 (-3500 2925);
PAINT MONO (-3500 2925);
DISPLAY INVISIBLE (-3500 2925);
FORCEPROP 1 LAST BODY_TYPE PLUMBING
J 0
(-3500 2975);
DISPLAY 0.872340 (-3500 2975);
PAINT GREEN (-3500 2975);
DISPLAY INVISIBLE (-3500 2975);
FORCEPROP 1 LAST HDL_TAP TRUE
J 0
(-3175 2800);
DISPLAY 0.872340 (-3175 2800);
DISPLAY INVISIBLE (-3175 2800);
FORCEPROP 1 LAST PATH I405
J 0
(-3502 2925);
DISPLAY 0.872340 (-3502 2925);
PAINT GREEN (-3502 2925);
DISPLAY INVISIBLE (-3502 2925);
FORCEADD TAP..1
(-3500 2825);
FORCEPROP 3 LASTPIN (-3550 2825) SIG_NAME M_D_CPU0_SB_DQS_DN<2>
J 0
(-3540 2835);
DISPLAY 0.659574 (-3540 2835);
PAINT MONO (-3540 2835);
DISPLAY INVISIBLE (-3540 2835);
FORCEPROP 1 LASTPIN (-3550 2825) BN 2
J 0
(-3562 2833);
DISPLAY 0.489362 (-3562 2833);
PAINT GREEN (-3562 2833);
FORCEPROP 2 LAST CDS_LIB mstr_standard
J 0
(-3500 2825);
DISPLAY 0.723404 (-3500 2825);
PAINT MONO (-3500 2825);
DISPLAY INVISIBLE (-3500 2825);
FORCEPROP 1 LAST BODY_TYPE PLUMBING
J 0
(-3500 2875);
DISPLAY 0.872340 (-3500 2875);
PAINT GREEN (-3500 2875);
DISPLAY INVISIBLE (-3500 2875);
FORCEPROP 1 LAST HDL_TAP TRUE
J 0
(-3175 2700);
DISPLAY 0.872340 (-3175 2700);
DISPLAY INVISIBLE (-3175 2700);
FORCEPROP 1 LAST PATH I406
J 0
(-3502 2825);
DISPLAY 0.872340 (-3502 2825);
PAINT GREEN (-3502 2825);
DISPLAY INVISIBLE (-3502 2825);
FORCEADD TAP..1
(-3500 2725);
FORCEPROP 3 LASTPIN (-3550 2725) SIG_NAME M_D_CPU0_SB_DQS_DN<1>
J 0
(-3540 2735);
DISPLAY 0.659574 (-3540 2735);
PAINT MONO (-3540 2735);
DISPLAY INVISIBLE (-3540 2735);
FORCEPROP 1 LASTPIN (-3550 2725) BN 1
J 0
(-3562 2733);
DISPLAY 0.489362 (-3562 2733);
PAINT GREEN (-3562 2733);
FORCEPROP 2 LAST CDS_LIB mstr_standard
J 0
(-3500 2725);
DISPLAY 0.723404 (-3500 2725);
PAINT MONO (-3500 2725);
DISPLAY INVISIBLE (-3500 2725);
FORCEPROP 1 LAST BODY_TYPE PLUMBING
J 0
(-3500 2775);
DISPLAY 0.872340 (-3500 2775);
PAINT GREEN (-3500 2775);
DISPLAY INVISIBLE (-3500 2775);
FORCEPROP 1 LAST HDL_TAP TRUE
J 0
(-3175 2600);
DISPLAY 0.872340 (-3175 2600);
DISPLAY INVISIBLE (-3175 2600);
FORCEPROP 1 LAST PATH I407
J 0
(-3502 2725);
DISPLAY 0.872340 (-3502 2725);
PAINT GREEN (-3502 2725);
DISPLAY INVISIBLE (-3502 2725);
FORCEADD TAP..1
(-3700 3175);
FORCEPROP 3 LASTPIN (-3750 3175) SIG_NAME M_D_CPU0_SB_DQS_DP<5>
J 0
(-3740 3185);
DISPLAY 0.659574 (-3740 3185);
PAINT MONO (-3740 3185);
DISPLAY INVISIBLE (-3740 3185);
FORCEPROP 1 LASTPIN (-3750 3175) BN 5
J 0
(-3762 3183);
DISPLAY 0.489362 (-3762 3183);
PAINT GREEN (-3762 3183);
FORCEPROP 2 LAST CDS_LIB mstr_standard
J 0
(-3700 3175);
DISPLAY 0.723404 (-3700 3175);
PAINT MONO (-3700 3175);
DISPLAY INVISIBLE (-3700 3175);
FORCEPROP 1 LAST BODY_TYPE PLUMBING
J 0
(-3700 3225);
DISPLAY 0.872340 (-3700 3225);
PAINT GREEN (-3700 3225);
DISPLAY INVISIBLE (-3700 3225);
FORCEPROP 1 LAST HDL_TAP TRUE
J 0
(-3375 3050);
DISPLAY 0.872340 (-3375 3050);
DISPLAY INVISIBLE (-3375 3050);
FORCEPROP 1 LAST PATH I408
J 0
(-3702 3175);
DISPLAY 0.872340 (-3702 3175);
PAINT GREEN (-3702 3175);
DISPLAY INVISIBLE (-3702 3175);
FORCEADD TAP..1
(-3700 3075);
FORCEPROP 3 LASTPIN (-3750 3075) SIG_NAME M_D_CPU0_SB_DQS_DP<4>
J 0
(-3740 3085);
DISPLAY 0.659574 (-3740 3085);
PAINT MONO (-3740 3085);
DISPLAY INVISIBLE (-3740 3085);
FORCEPROP 1 LASTPIN (-3750 3075) BN 4
J 0
(-3762 3083);
DISPLAY 0.489362 (-3762 3083);
PAINT GREEN (-3762 3083);
FORCEPROP 2 LAST CDS_LIB mstr_standard
J 0
(-3700 3075);
DISPLAY 0.723404 (-3700 3075);
PAINT MONO (-3700 3075);
DISPLAY INVISIBLE (-3700 3075);
FORCEPROP 1 LAST BODY_TYPE PLUMBING
J 0
(-3700 3125);
DISPLAY 0.872340 (-3700 3125);
PAINT GREEN (-3700 3125);
DISPLAY INVISIBLE (-3700 3125);
FORCEPROP 1 LAST HDL_TAP TRUE
J 0
(-3375 2950);
DISPLAY 0.872340 (-3375 2950);
DISPLAY INVISIBLE (-3375 2950);
FORCEPROP 1 LAST PATH I409
J 0
(-3702 3075);
DISPLAY 0.872340 (-3702 3075);
PAINT GREEN (-3702 3075);
DISPLAY INVISIBLE (-3702 3075);
FORCEADD TAP..1
(-3700 2875);
FORCEPROP 3 LASTPIN (-3750 2875) SIG_NAME M_D_CPU0_SB_DQS_DP<2>
J 0
(-3740 2885);
DISPLAY 0.659574 (-3740 2885);
PAINT MONO (-3740 2885);
DISPLAY INVISIBLE (-3740 2885);
FORCEPROP 1 LASTPIN (-3750 2875) BN 2
J 0
(-3762 2883);
DISPLAY 0.489362 (-3762 2883);
PAINT GREEN (-3762 2883);
FORCEPROP 2 LAST CDS_LIB mstr_standard
J 0
(-3700 2875);
DISPLAY 0.723404 (-3700 2875);
PAINT MONO (-3700 2875);
DISPLAY INVISIBLE (-3700 2875);
FORCEPROP 1 LAST BODY_TYPE PLUMBING
J 0
(-3700 2925);
DISPLAY 0.872340 (-3700 2925);
PAINT GREEN (-3700 2925);
DISPLAY INVISIBLE (-3700 2925);
FORCEPROP 1 LAST HDL_TAP TRUE
J 0
(-3375 2750);
DISPLAY 0.872340 (-3375 2750);
DISPLAY INVISIBLE (-3375 2750);
FORCEPROP 1 LAST PATH I410
J 0
(-3702 2875);
DISPLAY 0.872340 (-3702 2875);
PAINT GREEN (-3702 2875);
DISPLAY INVISIBLE (-3702 2875);
FORCEADD TAP..1
(-3700 2975);
FORCEPROP 3 LASTPIN (-3750 2975) SIG_NAME M_D_CPU0_SB_DQS_DP<3>
J 0
(-3740 2985);
DISPLAY 0.659574 (-3740 2985);
PAINT MONO (-3740 2985);
DISPLAY INVISIBLE (-3740 2985);
FORCEPROP 1 LASTPIN (-3750 2975) BN 3
J 0
(-3762 2983);
DISPLAY 0.489362 (-3762 2983);
PAINT GREEN (-3762 2983);
FORCEPROP 2 LAST CDS_LIB mstr_standard
J 0
(-3700 2975);
DISPLAY 0.723404 (-3700 2975);
PAINT MONO (-3700 2975);
DISPLAY INVISIBLE (-3700 2975);
FORCEPROP 1 LAST BODY_TYPE PLUMBING
J 0
(-3700 3025);
DISPLAY 0.872340 (-3700 3025);
PAINT GREEN (-3700 3025);
DISPLAY INVISIBLE (-3700 3025);
FORCEPROP 1 LAST HDL_TAP TRUE
J 0
(-3375 2850);
DISPLAY 0.872340 (-3375 2850);
DISPLAY INVISIBLE (-3375 2850);
FORCEPROP 1 LAST PATH I411
J 0
(-3702 2975);
DISPLAY 0.872340 (-3702 2975);
PAINT GREEN (-3702 2975);
DISPLAY INVISIBLE (-3702 2975);
FORCEADD TAP..1
(-3700 2775);
FORCEPROP 3 LASTPIN (-3750 2775) SIG_NAME M_D_CPU0_SB_DQS_DP<1>
J 0
(-3740 2785);
DISPLAY 0.659574 (-3740 2785);
PAINT MONO (-3740 2785);
DISPLAY INVISIBLE (-3740 2785);
FORCEPROP 1 LASTPIN (-3750 2775) BN 1
J 0
(-3762 2783);
DISPLAY 0.489362 (-3762 2783);
PAINT GREEN (-3762 2783);
FORCEPROP 2 LAST CDS_LIB mstr_standard
J 0
(-3700 2775);
DISPLAY 0.723404 (-3700 2775);
PAINT MONO (-3700 2775);
DISPLAY INVISIBLE (-3700 2775);
FORCEPROP 1 LAST BODY_TYPE PLUMBING
J 0
(-3700 2825);
DISPLAY 0.872340 (-3700 2825);
PAINT GREEN (-3700 2825);
DISPLAY INVISIBLE (-3700 2825);
FORCEPROP 1 LAST HDL_TAP TRUE
J 0
(-3375 2650);
DISPLAY 0.872340 (-3375 2650);
DISPLAY INVISIBLE (-3375 2650);
FORCEPROP 1 LAST PATH I412
J 0
(-3702 2775);
DISPLAY 0.872340 (-3702 2775);
PAINT GREEN (-3702 2775);
DISPLAY INVISIBLE (-3702 2775);
FORCEADD TAP..1
(-3500 2625);
FORCEPROP 3 LASTPIN (-3550 2625) SIG_NAME M_D_CPU0_SB_DQS_DN<0>
J 0
(-3540 2635);
DISPLAY 0.659574 (-3540 2635);
PAINT MONO (-3540 2635);
DISPLAY INVISIBLE (-3540 2635);
FORCEPROP 1 LASTPIN (-3550 2625) BN 0
J 0
(-3562 2633);
DISPLAY 0.489362 (-3562 2633);
PAINT GREEN (-3562 2633);
FORCEPROP 2 LAST CDS_LIB mstr_standard
J 0
(-3500 2625);
DISPLAY 0.723404 (-3500 2625);
PAINT MONO (-3500 2625);
DISPLAY INVISIBLE (-3500 2625);
FORCEPROP 1 LAST BODY_TYPE PLUMBING
J 0
(-3500 2675);
DISPLAY 0.872340 (-3500 2675);
PAINT GREEN (-3500 2675);
DISPLAY INVISIBLE (-3500 2675);
FORCEPROP 1 LAST HDL_TAP TRUE
J 0
(-3175 2500);
DISPLAY 0.872340 (-3175 2500);
DISPLAY INVISIBLE (-3175 2500);
FORCEPROP 1 LAST PATH I413
J 0
(-3502 2625);
DISPLAY 0.872340 (-3502 2625);
PAINT GREEN (-3502 2625);
DISPLAY INVISIBLE (-3502 2625);
FORCEADD TAP..1
(-3700 2675);
FORCEPROP 3 LASTPIN (-3750 2675) SIG_NAME M_D_CPU0_SB_DQS_DP<0>
J 0
(-3740 2685);
DISPLAY 0.659574 (-3740 2685);
PAINT MONO (-3740 2685);
DISPLAY INVISIBLE (-3740 2685);
FORCEPROP 1 LASTPIN (-3750 2675) BN 0
J 0
(-3762 2683);
DISPLAY 0.489362 (-3762 2683);
PAINT GREEN (-3762 2683);
FORCEPROP 2 LAST CDS_LIB mstr_standard
J 0
(-3700 2675);
DISPLAY 0.723404 (-3700 2675);
PAINT MONO (-3700 2675);
DISPLAY INVISIBLE (-3700 2675);
FORCEPROP 1 LAST BODY_TYPE PLUMBING
J 0
(-3700 2725);
DISPLAY 0.872340 (-3700 2725);
PAINT GREEN (-3700 2725);
DISPLAY INVISIBLE (-3700 2725);
FORCEPROP 1 LAST HDL_TAP TRUE
J 0
(-3375 2550);
DISPLAY 0.872340 (-3375 2550);
DISPLAY INVISIBLE (-3375 2550);
FORCEPROP 1 LAST PATH I414
J 0
(-3702 2675);
DISPLAY 0.872340 (-3702 2675);
PAINT GREEN (-3702 2675);
DISPLAY INVISIBLE (-3702 2675);
FORCEADD SCONN288_DDR506112002KQ..2
(-4650 3625);
FORCEPROP 1 LAST LOCATION J19
J 0
(-5250 4950);
DISPLAY 0.468085 (-5250 4950);
PAINT SKYBLUE (-5250 4950);
FORCEPROP 0 LAST $SEC 2
J 0
(-5100 5100);
DISPLAY 0.680851 (-5100 5100);
PAINT MONO (-5100 5100);
DISPLAY INVISIBLE (-5100 5100);
FORCEPROP 0 LAST CDS_SEC 2
J 0
(-5100 5100);
DISPLAY 1.021277 (-5100 5100);
DISPLAY INVISIBLE (-5100 5100);
FORCEPROP 0 LASTPIN (-3900 3675) $PN 12
J 0
(-3890 3685);
DISPLAY 0.680851 (-3890 3685);
PAINT MONO (-3890 3685);
FORCEPROP 0 LASTPIN (-3900 3725) $PN 11
J 0
(-3890 3735);
DISPLAY 0.680851 (-3890 3735);
PAINT MONO (-3890 3735);
FORCEPROP 0 LASTPIN (-3900 2625) $PN 105
J 0
(-3890 2635);
DISPLAY 0.680851 (-3890 2635);
PAINT MONO (-3890 2635);
FORCEPROP 0 LASTPIN (-3900 2675) $PN 104
J 0
(-3890 2685);
DISPLAY 0.680851 (-3890 2685);
PAINT MONO (-3890 2685);
FORCEPROP 0 LASTPIN (-3900 3775) $PN 23
J 0
(-3890 3785);
DISPLAY 0.680851 (-3890 3785);
PAINT MONO (-3890 3785);
FORCEPROP 0 LASTPIN (-3900 3825) $PN 22
J 0
(-3890 3835);
DISPLAY 0.680851 (-3890 3835);
PAINT MONO (-3890 3835);
FORCEPROP 0 LASTPIN (-3900 2725) $PN 116
J 0
(-3890 2735);
DISPLAY 0.680851 (-3890 2735);
PAINT MONO (-3890 2735);
FORCEPROP 0 LASTPIN (-3900 2775) $PN 115
J 0
(-3890 2785);
DISPLAY 0.680851 (-3890 2785);
PAINT MONO (-3890 2785);
FORCEPROP 0 LASTPIN (-3900 3875) $PN 34
J 0
(-3890 3885);
DISPLAY 0.680851 (-3890 3885);
PAINT MONO (-3890 3885);
FORCEPROP 0 LASTPIN (-3900 3925) $PN 33
J 0
(-3890 3935);
DISPLAY 0.680851 (-3890 3935);
PAINT MONO (-3890 3935);
FORCEPROP 0 LASTPIN (-3900 2825) $PN 127
J 0
(-3890 2835);
DISPLAY 0.680851 (-3890 2835);
PAINT MONO (-3890 2835);
FORCEPROP 0 LASTPIN (-3900 2875) $PN 126
J 0
(-3890 2885);
DISPLAY 0.680851 (-3890 2885);
PAINT MONO (-3890 2885);
FORCEPROP 0 LASTPIN (-3900 3975) $PN 45
J 0
(-3890 3985);
DISPLAY 0.680851 (-3890 3985);
PAINT MONO (-3890 3985);
FORCEPROP 0 LASTPIN (-3900 4025) $PN 44
J 0
(-3890 4035);
DISPLAY 0.680851 (-3890 4035);
PAINT MONO (-3890 4035);
FORCEPROP 0 LASTPIN (-3900 2925) $PN 138
J 0
(-3890 2935);
DISPLAY 0.680851 (-3890 2935);
PAINT MONO (-3890 2935);
FORCEPROP 0 LASTPIN (-3900 2975) $PN 137
J 0
(-3890 2985);
DISPLAY 0.680851 (-3890 2985);
PAINT MONO (-3890 2985);
FORCEPROP 0 LASTPIN (-3900 4075) $PN 56
J 0
(-3890 4085);
DISPLAY 0.680851 (-3890 4085);
PAINT MONO (-3890 4085);
FORCEPROP 0 LASTPIN (-3900 4125) $PN 55
J 0
(-3890 4135);
DISPLAY 0.680851 (-3890 4135);
PAINT MONO (-3890 4135);
FORCEPROP 0 LASTPIN (-3900 3025) $PN 238
J 0
(-3890 3035);
DISPLAY 0.680851 (-3890 3035);
PAINT MONO (-3890 3035);
FORCEPROP 0 LASTPIN (-3900 3075) $PN 239
J 0
(-3890 3085);
DISPLAY 0.680851 (-3890 3085);
PAINT MONO (-3890 3085);
FORCEPROP 0 LASTPIN (-3900 4175) $PN 156
J 0
(-3890 4185);
DISPLAY 0.680851 (-3890 4185);
PAINT MONO (-3890 4185);
FORCEPROP 0 LASTPIN (-3900 4225) $PN 157
J 0
(-3890 4235);
DISPLAY 0.680851 (-3890 4235);
PAINT MONO (-3890 4235);
FORCEPROP 0 LASTPIN (-3900 3125) $PN 249
J 0
(-3890 3135);
DISPLAY 0.680851 (-3890 3135);
PAINT MONO (-3890 3135);
FORCEPROP 0 LASTPIN (-3900 3175) $PN 250
J 0
(-3890 3185);
DISPLAY 0.680851 (-3890 3185);
PAINT MONO (-3890 3185);
FORCEPROP 0 LASTPIN (-3900 4275) $PN 167
J 0
(-3890 4285);
DISPLAY 0.680851 (-3890 4285);
PAINT MONO (-3890 4285);
FORCEPROP 0 LASTPIN (-3900 4325) $PN 168
J 0
(-3890 4335);
DISPLAY 0.680851 (-3890 4335);
PAINT MONO (-3890 4335);
FORCEPROP 0 LASTPIN (-3900 3225) $PN 260
J 0
(-3890 3235);
DISPLAY 0.680851 (-3890 3235);
PAINT MONO (-3890 3235);
FORCEPROP 0 LASTPIN (-3900 3275) $PN 261
J 0
(-3890 3285);
DISPLAY 0.680851 (-3890 3285);
PAINT MONO (-3890 3285);
FORCEPROP 0 LASTPIN (-3900 4375) $PN 178
J 0
(-3890 4385);
DISPLAY 0.680851 (-3890 4385);
PAINT MONO (-3890 4385);
FORCEPROP 0 LASTPIN (-3900 4425) $PN 179
J 0
(-3890 4435);
DISPLAY 0.680851 (-3890 4435);
PAINT MONO (-3890 4435);
FORCEPROP 0 LASTPIN (-3900 3325) $PN 271
J 0
(-3890 3335);
DISPLAY 0.680851 (-3890 3335);
PAINT MONO (-3890 3335);
FORCEPROP 0 LASTPIN (-3900 3375) $PN 272
J 0
(-3890 3385);
DISPLAY 0.680851 (-3890 3385);
PAINT MONO (-3890 3385);
FORCEPROP 0 LASTPIN (-3900 4475) $PN 189
J 0
(-3890 4485);
DISPLAY 0.680851 (-3890 4485);
PAINT MONO (-3890 4485);
FORCEPROP 0 LASTPIN (-3900 4525) $PN 190
J 0
(-3890 4535);
DISPLAY 0.680851 (-3890 4535);
PAINT MONO (-3890 4535);
FORCEPROP 0 LASTPIN (-3900 3425) $PN 282
J 0
(-3890 3435);
DISPLAY 0.680851 (-3890 3435);
PAINT MONO (-3890 3435);
FORCEPROP 0 LASTPIN (-3900 3475) $PN 283
J 0
(-3890 3485);
DISPLAY 0.680851 (-3890 3485);
PAINT MONO (-3890 3485);
FORCEPROP 0 LASTPIN (-3900 4575) $PN 200
J 0
(-3890 4585);
DISPLAY 0.680851 (-3890 4585);
PAINT MONO (-3890 4585);
FORCEPROP 0 LASTPIN (-3900 4625) $PN 201
J 0
(-3890 4635);
DISPLAY 0.680851 (-3890 4635);
PAINT MONO (-3890 4635);
FORCEPROP 0 LASTPIN (-3900 3525) $PN 94
J 0
(-3890 3535);
DISPLAY 0.680851 (-3890 3535);
PAINT MONO (-3890 3535);
FORCEPROP 0 LASTPIN (-3900 3575) $PN 93
J 0
(-3890 3585);
DISPLAY 0.680851 (-3890 3585);
PAINT MONO (-3890 3585);
FORCEPROP 2 LAST VALUE SCONN288_DDR506112002KQ
J 0
(-5100 5000);
DISPLAY 0.489362 (-5100 5000);
PAINT SKYBLUE (-5100 5000);
FORCEPROP 2 LAST PART_TYPE SMLF
J 0
(-5100 5050);
DISPLAY 1.021277 (-5100 5050);
FORCEPROP 1 LAST MATERIAL IO
J 0
(-5250 4800);
DISPLAY 0.468085 (-5250 4800);
PAINT SKYBLUE (-5250 4800);
FORCEPROP 1 LAST PART_NUMBER DFHST8FS479
J 0
(-5250 4875);
DISPLAY 0.468085 (-5250 4875);
PAINT SKYBLUE (-5250 4875);
FORCEPROP 1 LAST CDS_LMAN_SYM_OUTLINE -600,1150,600,-1150
J 0
(-4650 3625);
DISPLAY 0.468085 (-4650 3625);
PAINT GREEN (-4650 3625);
DISPLAY INVISIBLE (-4650 3625);
FORCEPROP 1 LAST PATH I415
J 0
(-4650 3625);
DISPLAY 0.723404 (-4650 3625);
PAINT GREEN (-4650 3625);
DISPLAY INVISIBLE (-4650 3625);
FORCEPROP 1 LAST NEEDS_NO_SIZE TRUE
J 0
(-4650 3625);
DISPLAY 0.723404 (-4650 3625);
PAINT GREEN (-4650 3625);
DISPLAY INVISIBLE (-4650 3625);
FORCEPROP 2 LAST CDS_LIB pure_quanta
J 0
(-4650 3625);
DISPLAY INVISIBLE (-4650 3625);
FORCEADD GND..1
(-2950 5225);
FORCEPROP 3 LASTPIN (-2950 5275) SIG_NAME GND\g
J 0
(-2940 5285);
DISPLAY 0.659574 (-2940 5285);
PAINT MONO (-2940 5285);
DISPLAY INVISIBLE (-2940 5285);
FORCEPROP 2 LAST CDS_LIB pure_quanta_power
J 0
(-2950 5225);
DISPLAY INVISIBLE (-2950 5225);
FORCEPROP 2 LAST BOM_COST MEM
J 0
(-2925 5350);
DISPLAY 0.659574 (-2925 5350);
DISPLAY INVISIBLE (-2925 5350);
FORCEPROP 1 LAST SIZE 1B
J 0
(-2875 5175);
DISPLAY 0.723404 (-2875 5175);
PAINT GREEN (-2875 5175);
DISPLAY INVISIBLE (-2875 5175);
FORCEPROP 1 LAST PATH I416
J 0
(-2875 5225);
DISPLAY 0.872340 (-2875 5225);
PAINT AQUA (-2875 5225);
DISPLAY INVISIBLE (-2875 5225);
FORCEPROP 2 LAST ROOM MEM_EFGH_DECOUPLING_CAPS
J 0
(-2925 5300);
DISPLAY 0.659574 (-2925 5300);
PAINT RED (-2925 5300);
DISPLAY INVISIBLE (-2925 5300);
FORCEPROP 1 LAST HDL_POWER GND
J 0
(-2950 5375);
DISPLAY 0.723404 (-2950 5375);
PAINT GREEN (-2950 5375);
DISPLAY INVISIBLE (-2950 5375);
FORCEADD Q_CAP..1
R 2
(-2950 5575);
FORCEPROP 1 LAST LOCATION C149
J 2
(-3000 5675);
DISPLAY 0.489362 (-3000 5675);
PAINT SKYBLUE (-3000 5675);
FORCEPROP 0 LAST $SEC 1
J 0
(-3000 5725);
DISPLAY 0.680851 (-3000 5725);
PAINT MONO (-3000 5725);
DISPLAY INVISIBLE (-3000 5725);
FORCEPROP 0 LAST CDS_SEC 1
J 0
(-3000 5725);
DISPLAY 0.680851 (-3000 5725);
DISPLAY INVISIBLE (-3000 5725);
FORCEPROP 1 LASTPIN (-2950 5675) $PN 1
J 2
(-2960 5655);
DISPLAY 0.489362 (-2960 5655);
PAINT MONO (-2960 5655);
FORCEPROP 1 LASTPIN (-2950 5475) $PN 2
J 2
(-2960 5455);
DISPLAY 0.489362 (-2960 5455);
PAINT MONO (-2960 5455);
FORCEPROP 1 LAST VALUE 10UF
J 2
(-3000 5625);
DISPLAY 0.489362 (-3000 5625);
PAINT SKYBLUE (-3000 5625);
FORCEPROP 1 LAST VOLTAGE 25V
J 2
(-3000 5575);
DISPLAY 0.489362 (-3000 5575);
PAINT SKYBLUE (-3000 5575);
FORCEPROP 1 LAST PACK_TYPE C0805
J 2
(-3000 5375);
DISPLAY 0.489362 (-3000 5375);
PAINT SKYBLUE (-3000 5375);
FORCEPROP 1 LAST MATERIAL X6S
J 2
(-3000 5475);
DISPLAY 0.489362 (-3000 5475);
PAINT SKYBLUE (-3000 5475);
FORCEPROP 1 LAST PART_NUMBER CH6104KEA00
J 2
(-3000 5425);
DISPLAY 0.489362 (-3000 5425);
PAINT SKYBLUE (-3000 5425);
FORCEPROP 1 LAST TOLERANCE 10%
J 2
(-3000 5525);
DISPLAY 0.489362 (-3000 5525);
PAINT SKYBLUE (-3000 5525);
FORCEPROP 0 LAST BOM_COST MEM
J 2
(-3005 5720);
DISPLAY 0.595745 (-3005 5720);
PAINT MONO (-3005 5720);
DISPLAY INVISIBLE (-3005 5720);
FORCEPROP 2 LAST CDS_LIB pure_quanta
J 0
(-2950 5575);
DISPLAY INVISIBLE (-2950 5575);
FORCEPROP 1 LAST PATH I417
J 2
(-3000 5725);
DISPLAY 0.978723 (-3000 5725);
PAINT WHITE (-3000 5725);
DISPLAY INVISIBLE (-3000 5725);
FORCEPROP 0 LAST ROOM MEM_CH_A_CPU0_DIMM1
J 2
(-3005 5720);
DISPLAY 0.595745 (-3005 5720);
PAINT RED (-3005 5720);
DISPLAY INVISIBLE (-3005 5720);
FORCEADD Q_CAP..1
R 2
(-2375 5575);
FORCEPROP 1 LAST LOCATION C150
J 2
(-2425 5675);
DISPLAY 0.489362 (-2425 5675);
PAINT SKYBLUE (-2425 5675);
FORCEPROP 0 LAST $SEC 1
J 0
(-2425 5725);
DISPLAY 0.680851 (-2425 5725);
PAINT MONO (-2425 5725);
DISPLAY INVISIBLE (-2425 5725);
FORCEPROP 0 LAST CDS_SEC 1
J 0
(-2425 5725);
DISPLAY 0.680851 (-2425 5725);
DISPLAY INVISIBLE (-2425 5725);
FORCEPROP 1 LASTPIN (-2375 5675) $PN 1
J 2
(-2385 5655);
DISPLAY 0.489362 (-2385 5655);
PAINT MONO (-2385 5655);
FORCEPROP 1 LASTPIN (-2375 5475) $PN 2
J 2
(-2385 5455);
DISPLAY 0.489362 (-2385 5455);
PAINT MONO (-2385 5455);
FORCEPROP 1 LAST MATERIAL X6S
J 2
(-2425 5475);
DISPLAY 0.489362 (-2425 5475);
PAINT SKYBLUE (-2425 5475);
FORCEPROP 1 LAST VALUE 10UF
J 2
(-2425 5625);
DISPLAY 0.489362 (-2425 5625);
PAINT SKYBLUE (-2425 5625);
FORCEPROP 1 LAST VOLTAGE 25V
J 2
(-2425 5575);
DISPLAY 0.489362 (-2425 5575);
PAINT SKYBLUE (-2425 5575);
FORCEPROP 1 LAST PACK_TYPE C0805
J 2
(-2425 5375);
DISPLAY 0.489362 (-2425 5375);
PAINT SKYBLUE (-2425 5375);
FORCEPROP 1 LAST TOLERANCE 10%
J 2
(-2425 5525);
DISPLAY 0.489362 (-2425 5525);
PAINT SKYBLUE (-2425 5525);
FORCEPROP 1 LAST PART_NUMBER CH6104KEA00
J 2
(-2425 5425);
DISPLAY 0.489362 (-2425 5425);
PAINT SKYBLUE (-2425 5425);
FORCEPROP 0 LAST BOM_COST MEM
J 2
(-2430 5720);
DISPLAY 0.595745 (-2430 5720);
PAINT MONO (-2430 5720);
DISPLAY INVISIBLE (-2430 5720);
FORCEPROP 2 LAST CDS_LIB pure_quanta
J 0
(-2375 5575);
DISPLAY INVISIBLE (-2375 5575);
FORCEPROP 1 LAST PATH I418
J 2
(-2425 5725);
DISPLAY 0.978723 (-2425 5725);
PAINT WHITE (-2425 5725);
DISPLAY INVISIBLE (-2425 5725);
FORCEPROP 0 LAST ROOM MEM_CH_A_CPU0_DIMM1
J 2
(-2430 5720);
DISPLAY 0.595745 (-2430 5720);
PAINT RED (-2430 5720);
DISPLAY INVISIBLE (-2430 5720);
FORCEADD UNIVERSAL_POWER..1
(-2950 5900);
FORCEPROP 3 LASTPIN (-2950 5850) SIG_NAME P12V_MEM_1\g
J 0
(-2940 5860);
DISPLAY 0.659574 (-2940 5860);
PAINT MONO (-2940 5860);
DISPLAY INVISIBLE (-2940 5860);
FORCEPROP 1 LAST HDL_POWER P12V_MEM_1
J 1
(-2975 5950);
DISPLAY 0.489362 (-2975 5950);
PAINT GREEN (-2975 5950);
FORCEPROP 2 LAST BOM_COST VR_SYSTEM
J 0
(-2950 6000);
DISPLAY 0.617021 (-2950 6000);
PAINT PURPLE (-2950 6000);
DISPLAY INVISIBLE (-2950 6000);
FORCEPROP 2 LAST CDS_LIB pure_quanta_power
J 0
(-2950 5900);
DISPLAY INVISIBLE (-2950 5900);
FORCEPROP 1 LAST PATH I419
J 0
(-2900 5925);
DISPLAY 0.872340 (-2900 5925);
PAINT AQUA (-2900 5925);
DISPLAY INVISIBLE (-2900 5925);
FORCEADD OFFPAGE..1
(-8375 2850);
FORCEPROP 2 LAST $XR5 90 
J 0
(-9107 2850);
DISPLAY 0.638298 (-9107 2850);
PAINT MONO (-9107 2850);
FORCEPROP 2 LAST $XR4 89 
J 0
(-9017 2850);
DISPLAY 0.638298 (-9017 2850);
PAINT MONO (-9017 2850);
FORCEPROP 2 LAST $XR3 87 
J 0
(-8927 2850);
DISPLAY 0.638298 (-8927 2850);
PAINT MONO (-8927 2850);
FORCEPROP 2 LAST $XR2 86 
J 0
(-8837 2850);
DISPLAY 0.638298 (-8837 2850);
PAINT MONO (-8837 2850);
FORCEPROP 2 LAST $XR1 85 
J 0
(-8747 2850);
DISPLAY 0.638298 (-8747 2850);
PAINT MONO (-8747 2850);
FORCEPROP 2 LAST $XR0 136 
J 0
(-8657 2850);
DISPLAY 0.638298 (-8657 2850);
PAINT MONO (-8657 2850);
FORCEPROP 2 LAST PATH I420
J 0
(-8650 2900);
DISPLAY 0.680851 (-8650 2900);
DISPLAY INVISIBLE (-8650 2900);
FORCEPROP 1 LAST COMMENT_BODY TRUE
J 0
(-8250 2750);
DISPLAY 0.872340 (-8250 2750);
PAINT GREEN (-8250 2750);
DISPLAY INVISIBLE (-8250 2750);
FORCEPROP 1 LAST OFFPAGE TRUE
J 0
(-8050 2725);
DISPLAY 0.872340 (-8050 2725);
PAINT GREEN (-8050 2725);
DISPLAY INVISIBLE (-8050 2725);
FORCEPROP 2 LAST CDS_LIB mstr_standard
J 0
(-8375 2850);
DISPLAY 0.808511 (-8375 2850);
DISPLAY INVISIBLE (-8375 2850);
FORCEADD Q_RES..1
(-7825 2850);
FORCEPROP 1 LAST $LOCATION R1
J 0
(-7875 2875);
DISPLAY 0.510638 (-7875 2875);
PAINT SKYBLUE (-7875 2875);
FORCEPROP 0 LAST CDS_LOCATION R1
J 0
(-7875 2950);
DISPLAY 0.680851 (-7875 2950);
DISPLAY INVISIBLE (-7875 2950);
FORCEPROP 0 LAST $SEC 1
J 0
(-7875 2950);
DISPLAY 0.680851 (-7875 2950);
PAINT MONO (-7875 2950);
DISPLAY INVISIBLE (-7875 2950);
FORCEPROP 0 LAST CDS_SEC 1
J 0
(-7875 2950);
DISPLAY 0.680851 (-7875 2950);
DISPLAY INVISIBLE (-7875 2950);
FORCEPROP 1 LASTPIN (-7925 2850) $PN 1
J 0
(-7913 2862);
DISPLAY 0.787234 (-7913 2862);
PAINT MONO (-7913 2862);
FORCEPROP 1 LASTPIN (-7725 2850) $PN 2
J 0
(-7763 2862);
DISPLAY 0.787234 (-7763 2862);
PAINT MONO (-7763 2862);
FORCEPROP 1 LAST VALUE 49.9
J 2
(-7675 2925);
DISPLAY 0.510638 (-7675 2925);
PAINT SKYBLUE (-7675 2925);
FORCEPROP 2 LAST CDS_LIB pure_quanta
J 0
(-7825 2850);
DISPLAY INVISIBLE (-7825 2850);
FORCEPROP 1 LAST PATH I421
J 0
(-7875 3000);
DISPLAY 0.978723 (-7875 3000);
PAINT WHITE (-7875 3000);
DISPLAY INVISIBLE (-7875 3000);
FORCEPROP 1 LAST PART_NUMBER CS04992FB07
J 0
(-7875 2950);
DISPLAY 0.978723 (-7875 2950);
DISPLAY INVISIBLE (-7875 2950);
FORCEPROP 1 LAST TOLERANCE 1%
J 0
(-7825 2750);
DISPLAY 0.978723 (-7825 2750);
DISPLAY INVISIBLE (-7825 2750);
FORCEPROP 1 LAST WATTAGE 1/16W
J 2
(-7850 2700);
DISPLAY 0.978723 (-7850 2700);
DISPLAY INVISIBLE (-7850 2700);
FORCEPROP 1 LAST PACK_TYPE 0402LF
J 0
(-7575 2700);
DISPLAY 0.978723 (-7575 2700);
DISPLAY INVISIBLE (-7575 2700);
FORCEPROP 1 LAST MATERIAL CHIP
J 0
(-7825 2700);
DISPLAY 0.978723 (-7825 2700);
DISPLAY INVISIBLE (-7825 2700);
FORCEADD QUANTA_TITLE_BLOCK_C..1
(-100 100);
FORCEPROP 0 LAST CDS_CON_LAST_MODIFIED Fri Mar 11 14:52:54 2022
J 0
(-1985 115);
DISPLAY INVISIBLE (-1985 115);
FORCEPROP 1 LAST CUSTOM_TXT_CDS <CON_LAST_MODIFIED>
J 0
(-1985 115);
DISPLAY 0.978723 (-1985 115);
FORCEPROP 2 LAST CUSTOM_TXT_CDS <XR_PAGE_TITLE>
J 0
(-7990 5350);
DISPLAY 0.638298 (-7990 5350);
PAINT PINK (-7990 5350);
DISPLAY INVISIBLE (-7990 5350);
FORCEPROP 1 LAST CUSTOM_TXT_CDS <NAME_2>
J 0
(-3275 150);
FORCEPROP 1 LAST CUSTOM_TXT_CDS <NAME_1>
J 0
(-3275 275);
FORCEPROP 1 LAST CUSTOM_TXT_CDS <Q_NUMBER>
J 0
(-1503 203);
DISPLAY 1.212766 (-1503 203);
FORCEPROP 1 LAST CUSTOM_TXT_CDS <Q_PROJ>
J 0
(-2482 202);
DISPLAY 1.212766 (-2482 202);
FORCEPROP 1 LAST CUSTOM_TXT_CDS <Q_REV>
J 0
(-284 203);
DISPLAY 1.212766 (-284 203);
FORCEPROP 1 LAST CUSTOM_TXT_CDS <CON_PAGE_NUM> OF <CON_TOTAL_PAGES>
J 0
(-546 118);
DISPLAY 0.978723 (-546 118);
FORCEPROP 1 LAST Q_DEPT BU9
J 1
(-3863 149);
DISPLAY 1.957447 (-3863 149);
PAINT GREEN (-3863 149);
FORCEPROP 1 LAST Q_TITLE DDR5 - CPU0 CHD
J 0
(-9425 150);
DISPLAY 2.446809 (-9425 150);
PAINT GREEN (-9425 150);
FORCEPROP 2 LAST PAGE_BORDER TRUE
J 0
(-7990 5350);
DISPLAY 0.638298 (-7990 5350);
PAINT PINK (-7990 5350);
DISPLAY INVISIBLE (-7990 5350);
FORCEPROP 1 LAST CDS_LMAN_SYM_OUTLINE -9475,6775,100,-125
J 0
(-100 100);
DISPLAY 0.468085 (-100 100);
PAINT GREEN (-100 100);
DISPLAY INVISIBLE (-100 100);
FORCEPROP 2 LAST CDS_LIB pure_quanta
J 0
(-100 100);
DISPLAY INVISIBLE (-100 100);
FORCEPROP 1 LAST COMMENT_BODY TRUE
J 0
(-88 87);
DISPLAY 0.978723 (-88 87);
PAINT GREEN (-88 87);
DISPLAY INVISIBLE (-88 87);
FORCEPROP 2 LAST CDS_XR_PAGE_TITLE CR-88 : @T6G_MB_LIB.T6G(SCH_1):PAGE88
J 0
(-7990 5350);
DISPLAY 0.638298 (-7990 5350);
PAINT PINK (-7990 5350);
DISPLAY INVISIBLE (-7990 5350);
FORCEADD DNS..2
(-8350 2450);
PAINT RED (-8350 2450);
FORCEPROP 2 LAST CDS_LIB mstr_misc
J 0
(-8350 2450);
DISPLAY INVISIBLE (-8350 2450);
FORCEPROP 1 LAST COMMENT_BODY TRUE
R 1
J 0
(-8275 2225);
DISPLAY 0.872340 (-8275 2225);
PAINT PEACH (-8275 2225);
DISPLAY INVISIBLE (-8275 2225);
WIRE 17 -1 (-7825 4175)(-7825 4125);
WIRE 17 -1 (-7825 4175)(-7825 4200);
WIRE 17 -1 (-7825 4075)(-7825 4125);
WIRE 17 -1 (-7825 4075)(-7825 4025);
WIRE 17 -1 (-7825 4200)(-8325 4200);
FORCEPROP 2 LAST SIG_NAME M_D_CPU0_SA_CB<7:0>
J 0
(-8275 4210);
DISPLAY 0.489362 (-8275 4210);
WIRE 17 -1 (-7825 3975)(-7825 4025);
WIRE 17 -1 (-7825 3925)(-7825 3975);
WIRE 17 -1 (-7825 3875)(-7825 3925);
WIRE 17 -1 (-7825 3825)(-7825 3875);
WIRE 17 -1 (-7825 3725)(-7825 3675);
WIRE 17 -1 (-7825 3725)(-7825 3750);
WIRE 17 -1 (-7825 3625)(-7825 3675);
WIRE 17 -1 (-7825 3625)(-7825 3575);
WIRE 17 -1 (-7825 3750)(-8325 3750);
FORCEPROP 2 LAST SIG_NAME M_D_CPU0_SB_CB<7:0>
J 0
(-8275 3760);
DISPLAY 0.489362 (-8275 3760);
WIRE 17 -1 (-7825 5275)(-7825 5325);
WIRE 17 -1 (-7825 5325)(-7825 5375);
WIRE 17 -1 (-7825 5375)(-7825 5425);
WIRE 17 -1 (-7825 5425)(-7825 5475);
WIRE 17 -1 (-7825 5475)(-7825 5525);
WIRE 17 -1 (-7825 5525)(-7825 5575);
WIRE 17 -1 (-7825 5575)(-7825 5600);
WIRE 17 -1 (-7825 5600)(-8325 5600);
FORCEPROP 2 LAST SIG_NAME M_D_CPU0_SA_CA<6:0>
J 0
(-8310 5610);
DISPLAY 0.489362 (-8310 5610);
WIRE 17 -1 (-7825 4875)(-7825 4925);
WIRE 17 -1 (-7825 4925)(-7825 4975);
WIRE 17 -1 (-7825 4975)(-7825 5025);
WIRE 17 -1 (-7825 5025)(-7825 5075);
WIRE 17 -1 (-7825 5075)(-7825 5125);
WIRE 17 -1 (-7825 5125)(-7825 5175);
WIRE 17 -1 (-7825 5175)(-7825 5200);
WIRE 17 -1 (-7825 5200)(-8325 5200);
FORCEPROP 2 LAST SIG_NAME M_D_CPU0_SB_CA<6:0>
J 0
(-8310 5210);
DISPLAY 0.489362 (-8310 5210);
WIRE 17 -1 (-7825 3525)(-7825 3575);
WIRE 17 -1 (-7825 3475)(-7825 3525);
WIRE 17 -1 (-7825 3425)(-7825 3475);
WIRE 17 -1 (-7825 3375)(-7825 3425);
WIRE 17 -1 (-6025 5525)(-6025 5475);
WIRE 17 -1 (-6025 5575)(-6025 5525);
WIRE 17 -1 (-6025 5475)(-6025 5425);
WIRE 17 -1 (-6025 5425)(-6025 5375);
WIRE 17 -1 (-6025 5600)(-6025 5575);
WIRE 17 -1 (-6025 5600)(-5575 5600);
FORCEPROP 2 LAST SIG_NAME M_D_CPU0_SA_DQ<31:0>
J 0
(-6010 5635);
DISPLAY 0.489362 (-6010 5635);
WIRE 17 -1 (-6025 5375)(-6025 5325);
WIRE 17 -1 (-6025 5325)(-6025 5275);
WIRE 17 -1 (-6025 5275)(-6025 5225);
WIRE 17 -1 (-6025 5225)(-6025 5175);
WIRE 17 -1 (-6025 5175)(-6025 5125);
WIRE 17 -1 (-6025 5125)(-6025 5075);
WIRE 17 -1 (-6025 5075)(-6025 5025);
WIRE 17 -1 (-6025 5025)(-6025 4975);
WIRE 17 -1 (-6025 4975)(-6025 4925);
WIRE 17 -1 (-6025 4925)(-6025 4875);
WIRE 17 -1 (-6025 4875)(-6025 4825);
WIRE 17 -1 (-6025 4775)(-6025 4825);
WIRE 17 -1 (-6025 4725)(-6025 4775);
WIRE 17 -1 (-6025 4675)(-6025 4725);
WIRE 17 -1 (-6025 4625)(-6025 4675);
WIRE 17 -1 (-6025 4625)(-6025 4575);
WIRE 17 -1 (-6025 4575)(-6025 4525);
WIRE 17 -1 (-6025 4525)(-6025 4475);
WIRE 17 -1 (-6025 4475)(-6025 4425);
WIRE 17 -1 (-6025 4425)(-6025 4375);
WIRE 17 -1 (-6025 4375)(-6025 4325);
WIRE 17 -1 (-6025 4325)(-6025 4275);
WIRE 17 -1 (-6025 4275)(-6025 4225);
WIRE 17 -1 (-6025 4175)(-6025 4225);
WIRE 17 -1 (-6025 4125)(-6025 4175);
WIRE 17 -1 (-6025 4075)(-6025 4125);
WIRE 17 -1 (-6025 4025)(-6025 4075);
WIRE 17 -1 (-6025 3925)(-6025 3875);
WIRE 17 -1 (-6025 3950)(-6025 3925);
WIRE 17 -1 (-6025 3875)(-6025 3825);
WIRE 17 -1 (-6025 3825)(-6025 3775);
WIRE 17 -1 (-6025 3950)(-5575 3950);
FORCEPROP 2 LAST SIG_NAME M_D_CPU0_SB_DQ<31:0>
J 0
(-6010 3985);
DISPLAY 0.489362 (-6010 3985);
WIRE 17 -1 (-6025 3775)(-6025 3725);
WIRE 17 -1 (-6025 3725)(-6025 3675);
WIRE 17 -1 (-6025 3675)(-6025 3625);
WIRE 17 -1 (-6025 3625)(-6025 3575);
WIRE 17 -1 (-6025 3575)(-6025 3525);
WIRE 17 -1 (-6025 3525)(-6025 3475);
WIRE 17 -1 (-6025 3475)(-6025 3425);
WIRE 17 -1 (-6025 3425)(-6025 3375);
WIRE 17 -1 (-6025 3375)(-6025 3325);
WIRE 17 -1 (-6025 3325)(-6025 3275);
WIRE 17 -1 (-6025 3275)(-6025 3225);
WIRE 17 -1 (-6025 3225)(-6025 3175);
WIRE 17 -1 (-6025 3125)(-6025 3175);
WIRE 17 -1 (-6025 3075)(-6025 3125);
WIRE 17 -1 (-6025 3025)(-6025 3075);
WIRE 17 -1 (-6025 2975)(-6025 3025);
WIRE 17 -1 (-6025 2975)(-6025 2925);
WIRE 17 -1 (-6025 2925)(-6025 2875);
WIRE 17 -1 (-6025 2875)(-6025 2825);
WIRE 17 -1 (-6025 2825)(-6025 2775);
WIRE 17 -1 (-6025 2775)(-6025 2725);
WIRE 17 -1 (-6025 2725)(-6025 2675);
WIRE 17 -1 (-6025 2675)(-6025 2625);
WIRE 17 -1 (-6025 2625)(-6025 2575);
WIRE 17 -1 (-6025 2525)(-6025 2575);
WIRE 17 -1 (-6025 2475)(-6025 2525);
WIRE 17 -1 (-6025 2425)(-6025 2475);
WIRE 17 -1 (-6025 2375)(-6025 2425);
WIRE 17 -1 (-3450 4400)(-3450 4300);
WIRE 17 -1 (-3450 4500)(-3450 4400);
WIRE 17 -1 (-3450 4300)(-3450 4200);
WIRE 17 -1 (-3450 4100)(-3450 4200);
WIRE 17 -1 (-3450 4600)(-3450 4500);
WIRE 17 -1 (-3450 4625)(-3450 4600);
WIRE 17 -1 (-3450 4000)(-3450 4100);
WIRE 17 -1 (-3450 3900)(-3450 4000);
WIRE 17 -1 (-3450 4625)(-2750 4625);
FORCEPROP 2 LAST SIG_NAME M_D_CPU0_SA_DQS_DN<9:0>
J 0
(-3385 4635);
DISPLAY 0.489362 (-3385 4635);
WIRE 17 -1 (-3650 4350)(-3650 4250);
WIRE 17 -1 (-3650 4450)(-3650 4350);
WIRE 17 -1 (-3650 4150)(-3650 4250);
WIRE 17 -1 (-3650 4050)(-3650 4150);
WIRE 17 -1 (-3650 4550)(-3650 4450);
WIRE 17 -1 (-3650 4650)(-3650 4550);
WIRE 17 -1 (-3650 3950)(-3650 4050);
WIRE 17 -1 (-3650 3950)(-3650 3850);
WIRE 17 -1 (-3650 4675)(-3650 4650);
WIRE 17 -1 (-3650 4675)(-2750 4675);
FORCEPROP 2 LAST SIG_NAME M_D_CPU0_SA_DQS_DP<9:0>
J 0
(-3385 4685);
DISPLAY 0.489362 (-3385 4685);
WIRE 17 -1 (-3450 3550)(-3450 3450);
WIRE 17 -1 (-3450 3575)(-3450 3550);
WIRE 17 -1 (-3450 3450)(-3450 3350);
WIRE 17 -1 (-3450 3350)(-3450 3250);
WIRE 17 -1 (-3450 3575)(-2750 3575);
FORCEPROP 2 LAST SIG_NAME M_D_CPU0_SB_DQS_DN<9:0>
J 0
(-3385 3585);
DISPLAY 0.489362 (-3385 3585);
WIRE 17 -1 (-3650 3400)(-3650 3300);
WIRE 17 -1 (-3650 3500)(-3650 3400);
WIRE 17 -1 (-3650 3300)(-3650 3200);
WIRE 17 -1 (-3650 3100)(-3650 3200);
WIRE 17 -1 (-3650 3600)(-3650 3500);
WIRE 17 -1 (-3650 3625)(-3650 3600);
WIRE 17 -1 (-3650 3000)(-3650 3100);
WIRE 17 -1 (-3650 2900)(-3650 3000);
WIRE 17 -1 (-3650 3625)(-2750 3625);
FORCEPROP 2 LAST SIG_NAME M_D_CPU0_SB_DQS_DP<9:0>
J 0
(-3385 3635);
DISPLAY 0.489362 (-3385 3635);
WIRE 17 -1 (-3650 3850)(-3650 3750);
WIRE 17 -1 (-3450 2750)(-3450 2650);
WIRE 17 -1 (-3450 2850)(-3450 2750);
WIRE 17 -1 (-3450 2850)(-3450 2950);
WIRE 17 -1 (-3450 2950)(-3450 3050);
WIRE 17 -1 (-3450 3050)(-3450 3150);
WIRE 17 -1 (-3450 3250)(-3450 3150);
WIRE 17 -1 (-3650 2800)(-3650 2700);
WIRE 17 -1 (-3650 2900)(-3650 2800);
WIRE 17 -1 (-3450 3900)(-3450 3800);
WIRE 17 -1 (-3450 3800)(-3450 3700);
WIRE 16 -1 (-6450 1225)(-6450 1325);
WIRE 16 -1 (-8600 3200)(-8600 3275);
WIRE 16 -1 (-8375 2550)(-8375 2575);
WIRE 16 -1 (-7925 2850)(-8325 2850);
FORCEPROP 2 LAST SIG_NAME I3C_SPD_DDRAF_CPU0_SCL
J 0
(-8360 2860);
DISPLAY 0.489362 (-8360 2860);
WIRE 16 -1 (-7625 2950)(-7625 2850);
WIRE 16 -1 (-7525 2950)(-7625 2950);
FORCEPROP 2 LAST SIG_NAME I3C_SPD_DDRD_CPU0_SCL
J 0
(-8010 2960);
DISPLAY 0.446809 (-8010 2960);
FORCEPROP 2 LASTPROP $XRERR UNIQUE?
J 0
(-8250 2960);
DISPLAY 0.638298 (-8250 2960);
PAINT MONO (-8250 2960);
DISPLAY INVISIBLE (-8250 2960);
WIRE 16 -1 (-7625 2850)(-7725 2850);
WIRE 16 -1 (-8175 2300)(-8375 2300);
WIRE 16 -1 (-8175 2300)(-8175 2700);
WIRE 16 -1 (-8375 2350)(-8375 2300);
WIRE 16 -1 (-8375 2300)(-8400 2300);
WIRE 16 -1 (-7525 2700)(-8175 2700);
FORCEPROP 2 LAST SIG_NAME PWRGD_CHD_CPU0_DIMM
J 0
(-8100 2710);
DISPLAY 0.489362 (-8100 2710);
FORCEPROP 2 LASTPROP $XRERR UNIQUE?
J 0
(-8340 2710);
DISPLAY 0.638298 (-8340 2710);
PAINT MONO (-8340 2710);
DISPLAY INVISIBLE (-8340 2710);
WIRE 16 -1 (-7525 3000)(-8325 3000);
FORCEPROP 2 LAST SIG_NAME I3C_SPD_DDRAF_CPU0_SDA
J 0
(-8335 3010);
DISPLAY 0.489362 (-8335 3010);
WIRE 16 -1 (-7525 3050)(-8325 3050);
FORCEPROP 2 LAST SIG_NAME PD_CHD_CPU0_DIMM_SAA
J 0
(-8300 3060);
DISPLAY 0.489362 (-8300 3060);
WIRE 16 -1 (-8600 3475)(-8600 3525);
WIRE 16 -1 (-8600 3525)(-8475 3525);
WIRE 16 -1 (-8475 3525)(-8475 3575);
WIRE 16 -1 (-8475 3525)(-8475 3100);
WIRE 16 -1 (-8475 3100)(-7525 3100);
WIRE 16 -1 (-7525 2600)(-8125 2600);
FORCEPROP 2 LAST SIG_NAME TP_CHD_CPU0_DIMM_RFU_6
J 0
(-8135 2610);
DISPLAY 0.489362 (-8135 2610);
FORCEPROP 2 LASTPROP $XRERR UNIQUE?
J 0
(-8365 2600);
DISPLAY 0.638298 (-8365 2600);
PAINT MONO (-8365 2600);
DISPLAY INVISIBLE (-8365 2600);
WIRE 16 -1 (-6125 5450)(-6325 5450);
WIRE 16 -1 (-6125 4600)(-6325 4600);
WIRE 16 -1 (-6125 4450)(-6325 4450);
WIRE 16 -1 (-6125 4400)(-6325 4400);
WIRE 16 -1 (-6325 4350)(-6125 4350);
WIRE 16 -1 (-6125 4300)(-6325 4300);
WIRE 16 -1 (-1950 5200)(-2250 5200);
WIRE 16 -1 (-2250 5200)(-2250 5150);
WIRE 16 -1 (-1950 5150)(-2250 5150);
WIRE 16 -1 (-2250 5150)(-2250 5100);
WIRE 16 -1 (-1950 5100)(-2250 5100);
WIRE 16 -1 (-2250 5100)(-2250 5050);
WIRE 16 -1 (-1950 5050)(-2250 5050);
WIRE 16 -1 (-2250 5050)(-2250 5000);
WIRE 16 -1 (-1950 5000)(-2250 5000);
WIRE 16 -1 (-2250 5000)(-2250 4950);
WIRE 16 -1 (-1950 4950)(-2250 4950);
WIRE 16 -1 (-2250 4950)(-2250 4900);
WIRE 16 -1 (-1950 4900)(-2250 4900);
WIRE 16 -1 (-2250 4900)(-2250 4850);
WIRE 16 -1 (-1950 4850)(-2250 4850);
WIRE 16 -1 (-2250 4850)(-2250 4800);
WIRE 16 -1 (-1950 4800)(-2250 4800);
WIRE 16 -1 (-2250 4800)(-2250 4750);
WIRE 16 -1 (-1950 4750)(-2250 4750);
WIRE 16 -1 (-2250 4750)(-2250 4700);
WIRE 16 -1 (-1950 4700)(-2250 4700);
WIRE 16 -1 (-2250 4700)(-2250 4650);
WIRE 16 -1 (-1950 4650)(-2250 4650);
WIRE 16 -1 (-2250 4650)(-2250 4600);
WIRE 16 -1 (-1950 4600)(-2250 4600);
WIRE 16 -1 (-2250 4600)(-2250 4550);
WIRE 16 -1 (-1950 4550)(-2250 4550);
WIRE 16 -1 (-2250 4550)(-2250 4500);
WIRE 16 -1 (-1950 4500)(-2250 4500);
WIRE 16 -1 (-2250 4500)(-2250 4450);
WIRE 16 -1 (-1950 4450)(-2250 4450);
WIRE 16 -1 (-2250 4450)(-2250 4400);
WIRE 16 -1 (-1950 4400)(-2250 4400);
WIRE 16 -1 (-2250 4400)(-2250 4350);
WIRE 16 -1 (-1950 4350)(-2250 4350);
WIRE 16 -1 (-2250 4350)(-2250 4300);
WIRE 16 -1 (-1950 4300)(-2250 4300);
WIRE 16 -1 (-2250 4300)(-2250 4250);
WIRE 16 -1 (-1950 4250)(-2250 4250);
WIRE 16 -1 (-2250 4250)(-2250 4200);
WIRE 16 -1 (-1950 4200)(-2250 4200);
WIRE 16 -1 (-2250 4200)(-2250 4150);
WIRE 16 -1 (-1950 4150)(-2250 4150);
WIRE 16 -1 (-2250 4150)(-2250 4100);
WIRE 16 -1 (-1950 4100)(-2250 4100);
WIRE 16 -1 (-2250 4100)(-2250 4050);
WIRE 16 -1 (-1950 4050)(-2250 4050);
WIRE 16 -1 (-2250 4050)(-2250 4000);
WIRE 16 -1 (-1950 4000)(-2250 4000);
WIRE 16 -1 (-2250 4000)(-2250 3950);
WIRE 16 -1 (-1950 3950)(-2250 3950);
WIRE 16 -1 (-2250 3950)(-2250 3900);
WIRE 16 -1 (-1950 3900)(-2250 3900);
WIRE 16 -1 (-2250 3900)(-2250 3850);
WIRE 16 -1 (-1950 3850)(-2250 3850);
WIRE 16 -1 (-2250 3850)(-2250 3800);
WIRE 16 -1 (-1950 3800)(-2250 3800);
WIRE 16 -1 (-2250 3800)(-2250 3750);
WIRE 16 -1 (-1950 3750)(-2250 3750);
WIRE 16 -1 (-2250 3750)(-2250 3700);
WIRE 16 -1 (-1950 3700)(-2250 3700);
WIRE 16 -1 (-2250 3700)(-2250 3650);
WIRE 16 -1 (-1950 3650)(-2250 3650);
WIRE 16 -1 (-2250 3650)(-2250 3600);
WIRE 16 -1 (-1950 3600)(-2250 3600);
WIRE 16 -1 (-2250 3600)(-2250 3550);
WIRE 16 -1 (-1950 3550)(-2250 3550);
WIRE 16 -1 (-2250 3550)(-2250 3500);
WIRE 16 -1 (-1950 3500)(-2250 3500);
WIRE 16 -1 (-2250 3500)(-2250 3450);
WIRE 16 -1 (-1950 3450)(-2250 3450);
WIRE 16 -1 (-2250 3450)(-2250 3400);
WIRE 16 -1 (-1950 3400)(-2250 3400);
WIRE 16 -1 (-2250 3400)(-2250 3350);
WIRE 16 -1 (-1950 3350)(-2250 3350);
WIRE 16 -1 (-2250 3350)(-2250 3300);
WIRE 16 -1 (-1950 3300)(-2250 3300);
WIRE 16 -1 (-2250 3300)(-2250 3250);
WIRE 16 -1 (-1950 3250)(-2250 3250);
WIRE 16 -1 (-2250 3250)(-2250 3200);
WIRE 16 -1 (-1950 3200)(-2250 3200);
WIRE 16 -1 (-2250 3200)(-2250 3150);
WIRE 16 -1 (-1950 3150)(-2250 3150);
WIRE 16 -1 (-2250 3150)(-2250 3100);
WIRE 16 -1 (-1950 3100)(-2250 3100);
WIRE 16 -1 (-2250 3100)(-2250 3050);
WIRE 16 -1 (-1950 3050)(-2250 3050);
WIRE 16 -1 (-2250 3050)(-2250 3000);
WIRE 16 -1 (-1950 3000)(-2250 3000);
WIRE 16 -1 (-2250 3000)(-2250 2950);
WIRE 16 -1 (-1950 2950)(-2250 2950);
WIRE 16 -1 (-2250 2950)(-2250 2900);
WIRE 16 -1 (-1950 2900)(-2250 2900);
WIRE 16 -1 (-2250 2900)(-2250 2850);
WIRE 16 -1 (-1950 2850)(-2250 2850);
WIRE 16 -1 (-2250 2850)(-2250 2800);
WIRE 16 -1 (-1950 2800)(-2250 2800);
WIRE 16 -1 (-2250 2800)(-2250 2750);
WIRE 16 -1 (-1950 2750)(-2250 2750);
WIRE 16 -1 (-2250 2750)(-2250 2700);
WIRE 16 -1 (-1950 2700)(-2250 2700);
WIRE 16 -1 (-2250 2700)(-2250 2650);
WIRE 16 -1 (-1950 2650)(-2250 2650);
WIRE 16 -1 (-2250 2650)(-2250 2600);
WIRE 16 -1 (-1950 2600)(-2250 2600);
WIRE 16 -1 (-2250 2600)(-2250 2550);
WIRE 16 -1 (-1950 2550)(-2250 2550);
WIRE 16 -1 (-2250 2550)(-2250 2500);
WIRE 16 -1 (-1950 2500)(-2250 2500);
WIRE 16 -1 (-2250 2500)(-2250 2450);
WIRE 16 -1 (-1950 2450)(-2250 2450);
WIRE 16 -1 (-2250 2450)(-2250 2400);
WIRE 16 -1 (-1950 2400)(-2250 2400);
WIRE 16 -1 (-2250 2400)(-2250 2350);
WIRE 16 -1 (-1950 2350)(-2250 2350);
WIRE 16 -1 (-2250 2350)(-2250 2300);
WIRE 16 -1 (-1950 2300)(-2250 2300);
WIRE 16 -1 (-2250 2300)(-2250 2250);
WIRE 16 -1 (-1950 2250)(-2250 2250);
WIRE 16 -1 (-2250 2250)(-2250 2200);
WIRE 16 -1 (-1950 2200)(-2250 2200);
WIRE 16 -1 (-2250 2200)(-2250 2150);
WIRE 16 -1 (-2250 2150)(-2250 2100);
WIRE 16 -1 (-1950 2150)(-2250 2150);
WIRE 16 -1 (-1950 2100)(-2250 2100);
WIRE 16 -1 (-2250 2100)(-2250 2000);
WIRE 16 -1 (-2375 5350)(-2950 5350);
WIRE 16 -1 (-2375 5350)(-2375 5475);
WIRE 16 -1 (-2950 5350)(-2950 5475);
WIRE 16 -1 (-2950 5350)(-2950 5275);
WIRE 16 -1 (-450 5350)(-450 5300);
WIRE 16 -1 (-450 5350)(-750 5350);
WIRE 16 -1 (-450 5300)(-450 5250);
WIRE 16 -1 (-450 5300)(-750 5300);
WIRE 16 -1 (-450 5250)(-450 5200);
WIRE 16 -1 (-450 5250)(-750 5250);
WIRE 16 -1 (-450 5200)(-450 5150);
WIRE 16 -1 (-450 5200)(-750 5200);
WIRE 16 -1 (-450 5150)(-750 5150);
WIRE 16 -1 (-450 5150)(-450 5100);
WIRE 16 -1 (-450 5100)(-450 5050);
WIRE 16 -1 (-450 5100)(-750 5100);
WIRE 16 -1 (-450 5050)(-450 5000);
WIRE 16 -1 (-450 5050)(-750 5050);
WIRE 16 -1 (-450 5000)(-450 4950);
WIRE 16 -1 (-450 5000)(-750 5000);
WIRE 16 -1 (-450 4950)(-450 4900);
WIRE 16 -1 (-450 4950)(-750 4950);
WIRE 16 -1 (-450 4900)(-450 4850);
WIRE 16 -1 (-450 4900)(-750 4900);
WIRE 16 -1 (-450 4850)(-450 4800);
WIRE 16 -1 (-450 4850)(-750 4850);
WIRE 16 -1 (-450 4800)(-450 4750);
WIRE 16 -1 (-450 4800)(-750 4800);
WIRE 16 -1 (-450 4750)(-450 4700);
WIRE 16 -1 (-450 4750)(-750 4750);
WIRE 16 -1 (-450 4700)(-450 4650);
WIRE 16 -1 (-450 4700)(-750 4700);
WIRE 16 -1 (-450 4650)(-450 4600);
WIRE 16 -1 (-450 4650)(-750 4650);
WIRE 16 -1 (-450 4600)(-450 4550);
WIRE 16 -1 (-450 4600)(-750 4600);
WIRE 16 -1 (-450 4550)(-450 4500);
WIRE 16 -1 (-450 4550)(-750 4550);
WIRE 16 -1 (-450 4500)(-450 4450);
WIRE 16 -1 (-450 4500)(-750 4500);
WIRE 16 -1 (-450 4450)(-450 4400);
WIRE 16 -1 (-450 4450)(-750 4450);
WIRE 16 -1 (-450 4400)(-450 4350);
WIRE 16 -1 (-450 4400)(-750 4400);
WIRE 16 -1 (-450 4350)(-450 4300);
WIRE 16 -1 (-450 4350)(-750 4350);
WIRE 16 -1 (-450 4300)(-450 4250);
WIRE 16 -1 (-450 4300)(-750 4300);
WIRE 16 -1 (-450 4250)(-450 4200);
WIRE 16 -1 (-450 4250)(-750 4250);
WIRE 16 -1 (-450 4200)(-450 4150);
WIRE 16 -1 (-450 4200)(-750 4200);
WIRE 16 -1 (-450 4150)(-450 4100);
WIRE 16 -1 (-450 4150)(-750 4150);
WIRE 16 -1 (-450 4100)(-750 4100);
WIRE 16 -1 (-450 4100)(-450 4050);
WIRE 16 -1 (-450 4050)(-450 4000);
WIRE 16 -1 (-450 4050)(-750 4050);
WIRE 16 -1 (-450 4000)(-450 3950);
WIRE 16 -1 (-450 4000)(-750 4000);
WIRE 16 -1 (-450 3950)(-450 3900);
WIRE 16 -1 (-450 3950)(-750 3950);
WIRE 16 -1 (-450 3900)(-450 3850);
WIRE 16 -1 (-450 3900)(-750 3900);
WIRE 16 -1 (-450 3850)(-450 3800);
WIRE 16 -1 (-450 3850)(-750 3850);
WIRE 16 -1 (-450 3800)(-450 3750);
WIRE 16 -1 (-450 3800)(-750 3800);
WIRE 16 -1 (-450 3750)(-450 3700);
WIRE 16 -1 (-450 3750)(-750 3750);
WIRE 16 -1 (-450 3700)(-450 3650);
WIRE 16 -1 (-450 3700)(-750 3700);
WIRE 16 -1 (-450 3650)(-450 3600);
WIRE 16 -1 (-450 3650)(-750 3650);
WIRE 16 -1 (-450 3600)(-450 3550);
WIRE 16 -1 (-450 3600)(-750 3600);
WIRE 16 -1 (-450 3550)(-450 3500);
WIRE 16 -1 (-450 3550)(-750 3550);
WIRE 16 -1 (-450 3500)(-450 3450);
WIRE 16 -1 (-450 3500)(-750 3500);
WIRE 16 -1 (-450 3450)(-450 3400);
WIRE 16 -1 (-450 3450)(-750 3450);
WIRE 16 -1 (-450 3400)(-450 3350);
WIRE 16 -1 (-450 3400)(-750 3400);
WIRE 16 -1 (-450 3350)(-450 3300);
WIRE 16 -1 (-450 3350)(-750 3350);
WIRE 16 -1 (-450 3300)(-450 3250);
WIRE 16 -1 (-450 3300)(-750 3300);
WIRE 16 -1 (-450 3250)(-450 3200);
WIRE 16 -1 (-450 3250)(-750 3250);
WIRE 16 -1 (-450 3200)(-450 3150);
WIRE 16 -1 (-450 3200)(-750 3200);
WIRE 16 -1 (-450 3150)(-450 3100);
WIRE 16 -1 (-450 3150)(-750 3150);
WIRE 16 -1 (-450 3100)(-750 3100);
WIRE 16 -1 (-450 3100)(-450 3050);
WIRE 16 -1 (-450 3050)(-450 3000);
WIRE 16 -1 (-450 3050)(-750 3050);
WIRE 16 -1 (-450 3000)(-450 2950);
WIRE 16 -1 (-450 3000)(-750 3000);
WIRE 16 -1 (-450 2950)(-450 2900);
WIRE 16 -1 (-450 2950)(-750 2950);
WIRE 16 -1 (-450 2900)(-450 2850);
WIRE 16 -1 (-450 2900)(-750 2900);
WIRE 16 -1 (-450 2850)(-450 2800);
WIRE 16 -1 (-450 2850)(-750 2850);
WIRE 16 -1 (-450 2800)(-450 2750);
WIRE 16 -1 (-450 2800)(-750 2800);
WIRE 16 -1 (-450 2750)(-450 2700);
WIRE 16 -1 (-450 2750)(-750 2750);
WIRE 16 -1 (-450 2700)(-450 2650);
WIRE 16 -1 (-450 2700)(-750 2700);
WIRE 16 -1 (-450 2650)(-450 2600);
WIRE 16 -1 (-450 2650)(-750 2650);
WIRE 16 -1 (-450 2600)(-450 2550);
WIRE 16 -1 (-450 2600)(-750 2600);
WIRE 16 -1 (-450 2550)(-450 2500);
WIRE 16 -1 (-450 2550)(-750 2550);
WIRE 16 -1 (-450 2500)(-450 2450);
WIRE 16 -1 (-450 2500)(-750 2500);
WIRE 16 -1 (-450 2450)(-450 2400);
WIRE 16 -1 (-450 2450)(-750 2450);
WIRE 16 -1 (-450 2400)(-450 2350);
WIRE 16 -1 (-450 2400)(-750 2400);
WIRE 16 -1 (-450 2350)(-450 2300);
WIRE 16 -1 (-450 2350)(-750 2350);
WIRE 16 -1 (-450 2300)(-450 2250);
WIRE 16 -1 (-450 2300)(-750 2300);
WIRE 16 -1 (-450 2250)(-450 2200);
WIRE 16 -1 (-450 2250)(-750 2250);
WIRE 16 -1 (-450 2200)(-450 2100);
WIRE 16 -1 (-450 2200)(-750 2200);
WIRE 16 -1 (-450 2100)(-450 2050);
WIRE 16 -1 (-450 2100)(-750 2100);
WIRE 16 -1 (-450 2050)(-450 2000);
WIRE 16 -1 (-450 2050)(-750 2050);
WIRE 16 -1 (-450 2000)(-450 1800);
WIRE 16 -1 (-450 2000)(-750 2000);
WIRE 16 -1 (-2250 5250)(-1950 5250);
WIRE 16 -1 (-2250 5300)(-2250 5250);
WIRE 16 -1 (-1950 5300)(-2250 5300);
WIRE 16 -1 (-2250 5300)(-2250 5350);
WIRE 16 -1 (-1950 5350)(-2250 5350);
WIRE 16 -1 (-2250 5350)(-2250 5775);
WIRE 16 -1 (-2375 5775)(-2250 5775);
WIRE 16 -1 (-2375 5775)(-2950 5775);
WIRE 16 -1 (-2375 5775)(-2375 5675);
WIRE 16 -1 (-2950 5775)(-2950 5850);
WIRE 16 -1 (-2950 5675)(-2950 5775);
WIRE 16 -1 (-3900 4575)(-3550 4575);
WIRE 16 -1 (-3750 3475)(-3900 3475);
WIRE 16 -1 (-3900 3525)(-3550 3525);
WIRE 16 -1 (-3900 3575)(-3750 3575);
WIRE 16 -1 (-3900 3675)(-3550 3675);
WIRE 16 -1 (-3900 3775)(-3550 3775);
WIRE 16 -1 (-3900 3825)(-3750 3825);
WIRE 16 -1 (-3900 4625)(-3750 4625);
WIRE 16 -1 (-3750 4525)(-3900 4525);
WIRE 16 -1 (-3900 4475)(-3550 4475);
WIRE 16 -1 (-3900 3325)(-3550 3325);
WIRE 16 -1 (-3750 4425)(-3900 4425);
WIRE 16 -1 (-3750 3275)(-3900 3275);
WIRE 16 -1 (-3900 3225)(-3550 3225);
WIRE 16 -1 (-3900 4275)(-3550 4275);
WIRE 16 -1 (-3900 3175)(-3750 3175);
WIRE 16 -1 (-3900 3125)(-3550 3125);
WIRE 16 -1 (-3900 4225)(-3750 4225);
WIRE 16 -1 (-3900 4175)(-3550 4175);
WIRE 16 -1 (-3750 3075)(-3900 3075);
WIRE 16 -1 (-3900 3025)(-3550 3025);
WIRE 16 -1 (-3750 4125)(-3900 4125);
WIRE 16 -1 (-3900 4075)(-3550 4075);
WIRE 16 -1 (-3750 2975)(-3900 2975);
WIRE 16 -1 (-3900 2925)(-3550 2925);
WIRE 16 -1 (-3750 4025)(-3900 4025);
WIRE 16 -1 (-3900 3975)(-3550 3975);
WIRE 16 -1 (-3750 2875)(-3900 2875);
WIRE 16 -1 (-3900 2825)(-3550 2825);
WIRE 16 -1 (-3750 3925)(-3900 3925);
WIRE 16 -1 (-3900 3875)(-3550 3875);
WIRE 16 -1 (-3900 2775)(-3750 2775);
WIRE 16 -1 (-3900 2725)(-3550 2725);
WIRE 16 -1 (-3750 2675)(-3900 2675);
WIRE 16 -1 (-3900 2625)(-3550 2625);
WIRE 16 -1 (-3750 3725)(-3900 3725);
WIRE 16 -1 (-3750 3375)(-3900 3375);
WIRE 16 -1 (-3900 3425)(-3550 3425);
WIRE 16 -1 (-3750 4325)(-3900 4325);
WIRE 16 -1 (-3900 4375)(-3550 4375);
WIRE 16 -1 (-7525 5550)(-7725 5550);
WIRE 16 -1 (-6325 5550)(-6125 5550);
WIRE 16 -1 (-6125 5300)(-6325 5300);
WIRE 16 -1 (-7525 2300)(-8125 2300);
FORCEPROP 2 LAST SIG_NAME TP_CHD_CPU0_DIMM_RFU_0
J 0
(-8135 2310);
DISPLAY 0.489362 (-8135 2310);
FORCEPROP 2 LASTPROP $XRERR UNIQUE?
J 0
(-8365 2300);
DISPLAY 0.638298 (-8365 2300);
PAINT MONO (-8365 2300);
DISPLAY INVISIBLE (-8365 2300);
WIRE 16 -1 (-7525 2350)(-8125 2350);
FORCEPROP 2 LAST SIG_NAME TP_CHD_CPU0_DIMM_RFU_1
J 0
(-8135 2360);
DISPLAY 0.489362 (-8135 2360);
FORCEPROP 2 LASTPROP $XRERR UNIQUE?
J 0
(-8365 2350);
DISPLAY 0.638298 (-8365 2350);
PAINT MONO (-8365 2350);
DISPLAY INVISIBLE (-8365 2350);
WIRE 16 -1 (-7525 2400)(-8125 2400);
FORCEPROP 2 LAST SIG_NAME TP_CHD_CPU0_DIMM_RFU_2
J 0
(-8135 2410);
DISPLAY 0.489362 (-8135 2410);
FORCEPROP 2 LASTPROP $XRERR UNIQUE?
J 0
(-8365 2400);
DISPLAY 0.638298 (-8365 2400);
PAINT MONO (-8365 2400);
DISPLAY INVISIBLE (-8365 2400);
WIRE 16 -1 (-7525 2450)(-8125 2450);
FORCEPROP 2 LAST SIG_NAME TP_CHD_CPU0_DIMM_RFU_3
J 0
(-8135 2460);
DISPLAY 0.489362 (-8135 2460);
FORCEPROP 2 LASTPROP $XRERR UNIQUE?
J 0
(-8365 2450);
DISPLAY 0.638298 (-8365 2450);
PAINT MONO (-8365 2450);
DISPLAY INVISIBLE (-8365 2450);
WIRE 16 -1 (-7525 2500)(-8125 2500);
FORCEPROP 2 LAST SIG_NAME TP_CHD_CPU0_DIMM_RFU_4
J 0
(-8135 2510);
DISPLAY 0.489362 (-8135 2510);
FORCEPROP 2 LASTPROP $XRERR UNIQUE?
J 0
(-8365 2500);
DISPLAY 0.638298 (-8365 2500);
PAINT MONO (-8365 2500);
DISPLAY INVISIBLE (-8365 2500);
WIRE 16 -1 (-7525 2550)(-8125 2550);
FORCEPROP 2 LAST SIG_NAME TP_CHD_CPU0_DIMM_RFU_5
J 0
(-8135 2560);
DISPLAY 0.489362 (-8135 2560);
FORCEPROP 2 LASTPROP $XRERR UNIQUE?
J 0
(-8365 2550);
DISPLAY 0.638298 (-8365 2550);
PAINT MONO (-8365 2550);
DISPLAY INVISIBLE (-8365 2550);
WIRE 16 -1 (-7525 3250)(-8050 3250);
FORCEPROP 2 LAST SIG_NAME M_D_CPU0_RESET_N
J 0
(-8035 3260);
DISPLAY 0.489362 (-8035 3260);
WIRE 16 -1 (-7525 4700)(-8325 4700);
FORCEPROP 2 LAST SIG_NAME M_D_CPU0_SB_PAR
J 0
(-8275 4710);
DISPLAY 0.489362 (-8275 4710);
WIRE 16 -1 (-7525 4750)(-8325 4750);
FORCEPROP 2 LAST SIG_NAME M_D_CPU0_SA_PAR
J 0
(-8275 4760);
DISPLAY 0.489362 (-8275 4760);
WIRE 16 -1 (-7525 2100)(-8325 2100);
FORCEPROP 2 LAST SIG_NAME M_D_CPU0_SB_RSP<0>
J 0
(-8275 2110);
DISPLAY 0.489362 (-8275 2110);
WIRE 16 -1 (-7525 2150)(-8325 2150);
FORCEPROP 2 LAST SIG_NAME M_D_CPU0_SA_RSP<0>
J 0
(-8275 2160);
DISPLAY 0.489362 (-8275 2160);
WIRE 16 -1 (-6125 2350)(-6325 2350);
WIRE 16 -1 (-6125 2400)(-6325 2400);
WIRE 16 -1 (-6125 2450)(-6325 2450);
WIRE 16 -1 (-6325 2500)(-6125 2500);
WIRE 16 -1 (-6125 2550)(-6325 2550);
WIRE 16 -1 (-6125 2600)(-6325 2600);
WIRE 16 -1 (-6125 2650)(-6325 2650);
WIRE 16 -1 (-6325 2700)(-6125 2700);
WIRE 16 -1 (-6125 2750)(-6325 2750);
WIRE 16 -1 (-6125 2800)(-6325 2800);
WIRE 16 -1 (-6125 2850)(-6325 2850);
WIRE 16 -1 (-6325 2900)(-6125 2900);
WIRE 16 -1 (-6125 2950)(-6325 2950);
WIRE 16 -1 (-6125 3000)(-6325 3000);
WIRE 16 -1 (-6125 3050)(-6325 3050);
WIRE 16 -1 (-6325 3100)(-6125 3100);
WIRE 16 -1 (-6125 3150)(-6325 3150);
WIRE 16 -1 (-6125 3200)(-6325 3200);
WIRE 16 -1 (-6125 3250)(-6325 3250);
WIRE 16 -1 (-6325 3300)(-6125 3300);
WIRE 16 -1 (-6125 3350)(-6325 3350);
WIRE 16 -1 (-6125 3400)(-6325 3400);
WIRE 16 -1 (-6125 3450)(-6325 3450);
WIRE 16 -1 (-6325 3500)(-6125 3500);
WIRE 16 -1 (-6125 3550)(-6325 3550);
WIRE 16 -1 (-6125 3600)(-6325 3600);
WIRE 16 -1 (-6125 3650)(-6325 3650);
WIRE 16 -1 (-6325 3700)(-6125 3700);
WIRE 16 -1 (-6125 3750)(-6325 3750);
WIRE 16 -1 (-6125 3800)(-6325 3800);
WIRE 16 -1 (-6125 3850)(-6325 3850);
WIRE 16 -1 (-6325 3900)(-6125 3900);
WIRE 16 -1 (-6125 4000)(-6325 4000);
WIRE 16 -1 (-6125 4050)(-6325 4050);
WIRE 16 -1 (-6125 4100)(-6325 4100);
WIRE 16 -1 (-6325 4150)(-6125 4150);
WIRE 16 -1 (-6125 4200)(-6325 4200);
WIRE 16 -1 (-6125 4250)(-6325 4250);
WIRE 16 -1 (-6125 4500)(-6325 4500);
WIRE 16 -1 (-6325 4550)(-6125 4550);
WIRE 16 -1 (-6125 4650)(-6325 4650);
WIRE 16 -1 (-6125 4700)(-6325 4700);
WIRE 16 -1 (-6325 4750)(-6125 4750);
WIRE 16 -1 (-6125 4800)(-6325 4800);
WIRE 16 -1 (-6125 4850)(-6325 4850);
WIRE 16 -1 (-6125 4900)(-6325 4900);
WIRE 16 -1 (-6325 4950)(-6125 4950);
WIRE 16 -1 (-6125 5000)(-6325 5000);
WIRE 16 -1 (-6125 5050)(-6325 5050);
WIRE 16 -1 (-6125 5100)(-6325 5100);
WIRE 16 -1 (-6325 5150)(-6125 5150);
WIRE 16 -1 (-6125 5200)(-6325 5200);
WIRE 16 -1 (-6125 5250)(-6325 5250);
WIRE 16 -1 (-6325 5350)(-6125 5350);
WIRE 16 -1 (-6125 5400)(-6325 5400);
WIRE 16 -1 (-6125 5500)(-6325 5500);
WIRE 16 -1 (-7525 4450)(-8325 4450);
FORCEPROP 2 LAST SIG_NAME M_D_CPU0_SB_CS_N<1>
J 0
(-8275 4460);
DISPLAY 0.489362 (-8275 4460);
WIRE 16 -1 (-7525 4600)(-8325 4600);
FORCEPROP 2 LAST SIG_NAME M_D_CPU0_SA_CS_N<1>
J 0
(-8275 4610);
DISPLAY 0.489362 (-8275 4610);
WIRE 16 -1 (-7525 4400)(-8325 4400);
FORCEPROP 2 LAST SIG_NAME M_D_CPU0_SB_CS_N<0>
J 0
(-8275 4410);
DISPLAY 0.489362 (-8275 4410);
WIRE 16 -1 (-7525 4550)(-8325 4550);
FORCEPROP 2 LAST SIG_NAME M_D_CPU0_SA_CS_N<0>
J 0
(-8275 4560);
DISPLAY 0.489362 (-8275 4560);
WIRE 16 -1 (-7525 4300)(-8325 4300);
FORCEPROP 2 LAST SIG_NAME M_D_CPU0_CLK_DP<0>
J 0
(-8275 4310);
DISPLAY 0.489362 (-8275 4310);
WIRE 16 -1 (-7525 4250)(-8325 4250);
FORCEPROP 2 LAST SIG_NAME M_D_CPU0_CLK_DN<0>
J 0
(-8275 4260);
DISPLAY 0.489362 (-8275 4260);
WIRE 16 -1 (-7525 3350)(-7725 3350);
WIRE 16 -1 (-7525 3400)(-7725 3400);
WIRE 16 -1 (-7525 3450)(-7725 3450);
WIRE 16 -1 (-7525 3500)(-7725 3500);
WIRE 16 -1 (-7525 3550)(-7725 3550);
WIRE 16 -1 (-7525 3600)(-7725 3600);
WIRE 16 -1 (-7525 3650)(-7725 3650);
WIRE 16 -1 (-7525 3800)(-7725 3800);
WIRE 16 -1 (-7525 3900)(-7725 3900);
WIRE 16 -1 (-7525 3950)(-7725 3950);
WIRE 16 -1 (-7525 4050)(-7725 4050);
WIRE 16 -1 (-7525 4100)(-7725 4100);
WIRE 16 -1 (-7525 5150)(-7725 5150);
WIRE 16 -1 (-7525 5100)(-7725 5100);
WIRE 16 -1 (-7525 5500)(-7725 5500);
WIRE 16 -1 (-7525 5050)(-7725 5050);
WIRE 16 -1 (-7525 5450)(-7725 5450);
WIRE 16 -1 (-7525 5000)(-7725 5000);
WIRE 16 -1 (-7525 5400)(-7725 5400);
WIRE 16 -1 (-7525 4950)(-7725 4950);
WIRE 16 -1 (-7525 5350)(-7725 5350);
WIRE 16 -1 (-7525 4900)(-7725 4900);
WIRE 16 -1 (-7525 5300)(-7725 5300);
WIRE 16 -1 (-7525 4850)(-7725 4850);
WIRE 16 -1 (-7525 5250)(-7725 5250);
WIRE 16 -1 (-7525 3200)(-8050 3200);
FORCEPROP 2 LAST SIG_NAME M_D_CPU0_ALERT_N
J 0
(-8035 3210);
DISPLAY 0.489362 (-8035 3210);
WIRE 16 -1 (-7525 3700)(-7725 3700);
WIRE 16 -1 (-7525 3850)(-7725 3850);
WIRE 16 -1 (-7525 4000)(-7725 4000);
WIRE 16 -1 (-7525 4150)(-7725 4150);
WIRE 16 -1 (-8950 2300)(-8600 2300);
FORCEPROP 2 LAST SIG_NAME PWRGD_CHAF_CPU0
J 0
(-8935 2310);
DISPLAY 0.489362 (-8935 2310);
WIRE 16 -1 (-6450 1600)(-6450 1525);
WIRE 16 -1 (-6450 1600)(-7175 1600);
FORCEPROP 2 LAST SIG_NAME PD_CHD_CPU0_DIMM_SAA
J 0
(-7160 1610);
DISPLAY 0.489362 (-7160 1610);
DOT 1 (-2375 5775);
DOT 1 (-2950 5775);
DOT 1 (-2950 5350);
DOT 1 (-2250 5350);
DOT 1 (-2250 4600);
DOT 1 (-8375 2300);
DOT 1 (-8475 3525);
DOT 1 (-2250 2100);
DOT 1 (-2250 2150);
DOT 1 (-2250 2200);
DOT 1 (-2250 2250);
DOT 1 (-2250 2300);
DOT 1 (-2250 2350);
DOT 1 (-2250 2400);
DOT 1 (-2250 2450);
DOT 1 (-2250 2500);
DOT 1 (-2250 2550);
DOT 1 (-2250 2600);
DOT 1 (-2250 2700);
DOT 1 (-2250 2650);
DOT 1 (-2250 2750);
DOT 1 (-2250 2800);
DOT 1 (-2250 2850);
DOT 1 (-2250 2900);
DOT 1 (-2250 2950);
DOT 1 (-2250 3000);
DOT 1 (-2250 3050);
DOT 1 (-2250 3100);
DOT 1 (-2250 3200);
DOT 1 (-2250 3150);
DOT 1 (-2250 3250);
DOT 1 (-2250 3300);
DOT 1 (-2250 3350);
DOT 1 (-2250 3400);
DOT 1 (-2250 3450);
DOT 1 (-2250 3500);
DOT 1 (-2250 3550);
DOT 1 (-2250 3600);
DOT 1 (-2250 3650);
DOT 1 (-2250 3700);
DOT 1 (-2250 3750);
DOT 1 (-2250 3800);
DOT 1 (-2250 3850);
DOT 1 (-2250 3900);
DOT 1 (-2250 3950);
DOT 1 (-2250 4000);
DOT 1 (-2250 4050);
DOT 1 (-2250 4100);
DOT 1 (-450 2050);
DOT 1 (-450 2000);
DOT 1 (-450 2100);
DOT 1 (-450 2200);
DOT 1 (-450 2250);
DOT 1 (-450 2300);
DOT 1 (-450 2350);
DOT 1 (-450 2450);
DOT 1 (-450 2400);
DOT 1 (-450 2500);
DOT 1 (-450 2550);
DOT 1 (-450 2600);
DOT 1 (-450 2700);
DOT 1 (-450 2650);
DOT 1 (-450 2750);
DOT 1 (-450 2800);
DOT 1 (-450 2850);
DOT 1 (-450 2950);
DOT 1 (-450 2900);
DOT 1 (-450 3000);
DOT 1 (-450 3050);
DOT 1 (-450 3100);
DOT 1 (-450 3150);
DOT 1 (-450 3250);
DOT 1 (-450 3200);
DOT 1 (-450 3350);
DOT 1 (-450 3300);
DOT 1 (-450 3400);
DOT 1 (-450 3450);
DOT 1 (-450 3500);
DOT 1 (-450 3600);
DOT 1 (-450 3550);
DOT 1 (-450 3650);
DOT 1 (-450 3700);
DOT 1 (-450 3750);
DOT 1 (-450 3850);
DOT 1 (-450 3800);
DOT 1 (-450 3900);
DOT 1 (-450 3950);
DOT 1 (-450 4000);
DOT 1 (-450 4150);
DOT 1 (-2250 4150);
DOT 1 (-2250 4200);
DOT 1 (-2250 4250);
DOT 1 (-2250 4300);
DOT 1 (-2250 4350);
DOT 1 (-2250 4450);
DOT 1 (-2250 4500);
DOT 1 (-2250 4900);
DOT 1 (-2250 5000);
DOT 1 (-2250 5100);
DOT 1 (-2250 5150);
DOT 1 (-2250 5300);
DOT 1 (-450 4200);
DOT 1 (-450 4250);
DOT 1 (-450 4300);
DOT 1 (-450 4350);
DOT 1 (-450 4400);
DOT 1 (-450 4500);
DOT 1 (-450 4450);
DOT 1 (-450 4550);
DOT 1 (-450 4600);
DOT 1 (-450 4650);
DOT 1 (-450 4750);
DOT 1 (-450 4700);
DOT 1 (-450 4800);
DOT 1 (-450 4850);
DOT 1 (-450 4900);
DOT 1 (-450 5000);
DOT 1 (-450 4950);
DOT 1 (-450 5050);
DOT 1 (-450 5100);
DOT 1 (-450 5150);
DOT 1 (-450 5200);
DOT 1 (-450 5250);
DOT 1 (-450 5300);
DOT 1 (-2250 4400);
DOT 1 (-450 4100);
DOT 1 (-450 4050);
DOT 1 (-2250 5050);
DOT 1 (-2250 4950);
DOT 1 (-2250 4850);
DOT 1 (-2250 4800);
DOT 1 (-2250 4700);
DOT 1 (-2250 4550);
DOT 1 (-2250 4650);
DOT 1 (-2250 4750);
QUIT
